G04 ================== begin FILE IDENTIFICATION RECORD ==================*
G04 Layout Name:  DAT6MTH3AD0_t6m_cm_d_brd_103112_274.brd*
G04 Film Name:    pmt*
G04 File Format:  Gerber RS274X*
G04 File Origin:  Cadence Allegro 16.3-S048*
G04 Origin Date:  Tue Nov 26 10:18:25 2013*
G04 *
G04 Layer:  VIA CLASS/PASTEMASK_TOP*
G04 Layer:  PIN/PASTEMASK_TOP*
G04 Layer:  PACKAGE GEOMETRY/PASTEMASK_TOP*
G04 Layer:  MANUFACTURING/PHOTOPLOT_OUTLINE*
G04 Layer:  DRAWING FORMAT/TITLE_BLOCK*
G04 Layer:  DRAWING FORMAT/TITLE_DATA_PMT*
G04 *
G04 Offset:    (0.00 0.00)*
G04 Mirror:    No*
G04 Mode:      Positive*
G04 Rotation:  0*
G04 FullContactRelief:  No*
G04 UndefLineWidth:     6.00*
G04 ================== end FILE IDENTIFICATION RECORD ====================*
%FSLAX25Y25*MOIN*%
%IR0*IPPOS*OFA0.00000B0.00000*MIA0B0*SFA1.00000B1.00000*%
%AMMACRO79*
4,1,24,.0315,-.0315,
.00394,-.0315,
.00394,-.009,
-.00394,-.009,
-.00394,-.0315,
-.0315,-.0315,
-.0315,-.00394,
-.009,-.00394,
-.009,.00394,
-.0315,.00394,
-.0315,.0315,
-.00394,.0315,
-.00394,.009,
-.00394,.00394,
-.00394,-.00394,
.00394,-.00394,
.00394,.00394,
.00394,.009,
.00394,.0315,
.0315,.0315,
.0315,.00394,
.009,.00394,
.009,-.00394,
.0315,-.00394,
.0315,-.0315,
0.0*
%
%ADD79MACRO79*%
%ADD22O,.04X.135*%
%ADD93R,.02X.004*%
%ADD153R,.126X.04*%
%ADD10R,.006X.012*%
%ADD111R,.04X.109*%
%AMMACRO56*
4,1,28,.04488,-.04823,
.02854,-.04823,
.02854,-.06319,
.01162,-.06319,
.01162,-.04823,
-.03307,-.04823,
-.03307,-.04626,
-.04488,-.04626,
-.04488,-.03051,
-.03307,-.03051,
-.03307,-.02067,
-.04488,-.02067,
-.04488,-.00492,
-.03307,-.00492,
-.03307,.00492,
-.04488,.00492,
-.04488,.02067,
-.03307,.02067,
-.03307,.03051,
-.04488,.03051,
-.04488,.04626,
-.03307,.04626,
-.03307,.04823,
.01162,.04823,
.01162,.06319,
.02854,.06319,
.02854,.04823,
.04488,.04823,
.04488,-.04823,
0.0*
%
%ADD56MACRO56*%
%ADD160R,.04X.007*%
%AMMACRO97*
4,1,28,-.04823,-.04488,
-.04823,-.02854,
-.06319,-.02854,
-.06319,-.01162,
-.04823,-.01162,
-.04823,.03307,
-.04626,.03307,
-.04626,.04488,
-.03051,.04488,
-.03051,.03307,
-.02067,.03307,
-.02067,.04488,
-.00492,.04488,
-.00492,.03307,
.00492,.03307,
.00492,.04488,
.02067,.04488,
.02067,.03307,
.03051,.03307,
.03051,.04488,
.04626,.04488,
.04626,.03307,
.04823,.03307,
.04823,-.01162,
.06319,-.01162,
.06319,-.02854,
.04823,-.02854,
.04823,-.04488,
-.04823,-.04488,
0.0*
%
%ADD97MACRO97*%
%AMMACRO169*
21,1,.016,.0041,0.0,0.0,45.*%
%ADD169MACRO169*%
%ADD163O,.119X.063*%
%ADD159R,.007X.04*%
%ADD103R,.005X.016*%
%ADD95R,.111X.095*%
%ADD89C,.03*%
%ADD77C,.012*%
%ADD42R,.0041X.016*%
%ADD32R,.048X.13*%
%ADD172O,.063X.119*%
%ADD152R,.0042X.016*%
%ADD135R,.06X.007*%
%ADD121R,.135X.072*%
%ADD102R,.016X.005*%
%ADD53R,.016X.0041*%
%ADD26R,.095X.111*%
%ADD138R,.007X.06*%
%ADD128R,.032X.166*%
%ADD94R,.016X.0042*%
%ADD156C,.042*%
%ADD147R,.044X.007*%
%ADD137R,.035X.007*%
%ADD91C,.015*%
%ADD12C,.06*%
%ADD150C,.052*%
%ADD146R,.007X.044*%
%ADD145C,.061*%
%ADD140R,.007X.035*%
%ADD75C,.016*%
%ADD59R,.036X.007*%
%ADD52R,.105X.069*%
%ADD60R,.007X.036*%
%ADD55R,.069X.105*%
%ADD51R,.15X.079*%
%ADD175R,.079X.15*%
%ADD161R,.047X.007*%
%ADD120R,.038X.007*%
%ADD20C,.045*%
%ADD158R,.007X.047*%
%ADD124R,.007X.038*%
%ADD110R,.055X.009*%
%ADD66C,.0145*%
%ADD46R,.13X.0848*%
%ADD109R,.009X.055*%
%ADD84R,.0848X.13*%
%ADD139C,.066*%
%ADD129R,.128X.069*%
%ADD101R,.032X.032*%
%ADD34C,.039*%
%ADD171C,.058*%
%ADD166C,.0193*%
%ADD155R,.042X.042*%
%ADD154C,.076*%
%ADD118R,.024X.024*%
%ADD11R,.06X.06*%
%ADD151R,.052X.052*%
%ADD144R,.061X.061*%
%ADD44C,.068*%
%ADD13C,.077*%
%AMMACRO72*
4,1,17,-.03445,.01132,
-.03445,-.01132,
.03445,-.01132,
.03445,.01132,
.01673,.01132,
.01673,.00709,
.01673,.00423,
.00886,.00423,
.00886,.00709,
.00886,.01132,
-.00886,.01132,
-.00886,.00709,
-.00886,.00423,
-.01673,.00423,
-.01673,.00709,
-.01673,.01132,
-.01675,.01132,
-.03445,.01132,
0.0*
%
%ADD72MACRO72*%
%ADD61R,.071X.071*%
%ADD23R,.045X.045*%
%ADD136R,.064X.064*%
%ADD86R,.083X.083*%
%ADD37R,.065X.065*%
%ADD143R,.066X.066*%
%ADD173R,.058X.058*%
%ADD43R,.068X.068*%
%ADD24R,.077X.077*%
%ADD69R,.087X.087*%
%ADD122R,.02X.01*%
%AMMACRO107*
4,1,24,-.0315,.0315,
-.00394,.0315,
-.00394,.009,
.00394,.009,
.00394,.0315,
.0315,.0315,
.0315,.00394,
.009,.00394,
.009,-.00394,
.0315,-.00394,
.0315,-.0315,
.00394,-.0315,
.00394,-.009,
.00394,-.00394,
.00394,.00394,
-.00394,.00394,
-.00394,-.00394,
-.00394,-.009,
-.00394,-.0315,
-.0315,-.0315,
-.0315,-.00394,
-.009,-.00394,
-.009,.00394,
-.0315,.00394,
-.0315,.0315,
0.0*
%
%ADD107MACRO107*%
%ADD81R,.033X.01*%
%ADD65O,.0135X.01*%
%ADD62R,.02X.014*%
%ADD119R,.041X.03*%
%ADD115R,.024X.02*%
%ADD96R,.014X.02*%
%ADD85O,.01X.0135*%
%ADD80R,.01X.033*%
%ADD126R,.02X.024*%
%ADD116R,.02X.016*%
%ADD78O,.0135X.011*%
%ADD76O,.011X.0135*%
%ADD31R,.05X.04*%
%ADD133R,.071X.011*%
%AMMACRO100*
4,1,28,-.04488,.04823,
-.02854,.04823,
-.02854,.06319,
-.01162,.06319,
-.01162,.04823,
.03307,.04823,
.03307,.04626,
.04488,.04626,
.04488,.03051,
.03307,.03051,
.03307,.02067,
.04488,.02067,
.04488,.00492,
.03307,.00492,
.03307,-.00492,
.04488,-.00492,
.04488,-.02067,
.03307,-.02067,
.03307,-.03051,
.04488,-.03051,
.04488,-.04626,
.03307,-.04626,
.03307,-.04823,
-.01162,-.04823,
-.01162,-.06319,
-.02854,-.06319,
-.02854,-.04823,
-.04488,-.04823,
-.04488,.04823,
0.0*
%
%ADD100MACRO100*%
%AMMACRO99*
4,1,28,.04823,.04488,
.04823,.02854,
.06319,.02854,
.06319,.01162,
.04823,.01162,
.04823,-.03307,
.04626,-.03307,
.04626,-.04488,
.03051,-.04488,
.03051,-.03307,
.02067,-.03307,
.02067,-.04488,
.00492,-.04488,
.00492,-.03307,
-.00492,-.03307,
-.00492,-.04488,
-.02067,-.04488,
-.02067,-.03307,
-.03051,-.03307,
-.03051,-.04488,
-.04626,-.04488,
-.04626,-.03307,
-.04823,-.03307,
-.04823,.01162,
-.06319,.01162,
-.06319,.02854,
-.04823,.02854,
-.04823,.04488,
.04823,.04488,
0.0*
%
%ADD99MACRO99*%
%ADD67R,.036X.01*%
%ADD16R,.04X.05*%
%ADD168R,.022X.024*%
%ADD134R,.011X.071*%
%ADD68R,.01X.036*%
%ADD38R,.036X.011*%
%ADD18R,.02X.018*%
%AMMACRO142*
21,1,.016,.005,0.0,0.0,135.*%
%ADD142MACRO142*%
%ADD132R,.034X.032*%
%ADD117R,.09X.011*%
%ADD113R,.061X.014*%
%ADD108R,.071X.04*%
%ADD41R,.061X.032*%
%ADD39R,.011X.036*%
%ADD36R,.022X.017*%
%ADD17R,.018X.02*%
%ADD167R,.032X.061*%
%ADD88O,.028X.015*%
%ADD71R,.017X.022*%
%ADD21R,.022X.053*%
%ADD170C,.14*%
%ADD98R,.036X.032*%
%ADD87O,.015X.028*%
%ADD82R,.046X.013*%
%ADD19R,.014X.044*%
%ADD14R,.08X.06*%
%ADD165R,.016X.052*%
%ADD70R,.036X.024*%
%ADD58R,.011X.057*%
%ADD33R,.032X.036*%
%ADD28R,.032X.028*%
%ADD157R,.052X.018*%
%ADD123R,.115X.166*%
%ADD104R,.059X.011*%
%ADD64R,.015X.081*%
%ADD50R,.017X.052*%
%ADD30R,.028X.032*%
%ADD106R,.011X.059*%
%ADD90R,.018X.052*%
%ADD57R,.054X.044*%
%ADD131C,.306*%
%ADD114R,.068X.022*%
%ADD40R,.044X.054*%
%ADD29R,.062X.046*%
%ADD130R,.059X.014*%
%ADD45R,.022X.068*%
%ADD27R,.046X.062*%
%ADD127R,.044X.056*%
%ADD15R,.014X.059*%
%ADD54R,.182X.185*%
%ADD112R,.026X.076*%
%ADD83R,.213X.213*%
%ADD164R,.071X.095*%
%ADD148R,.048X.038*%
%ADD92R,.056X.048*%
%AMMACRO47*
4,1,17,.01132,.03445,
-.01132,.03445,
-.01132,-.03445,
.01132,-.03445,
.01132,-.01673,
.00709,-.01673,
.00423,-.01673,
.00423,-.00886,
.00709,-.00886,
.01132,-.00886,
.01132,.00886,
.00709,.00886,
.00423,.00886,
.00423,.01673,
.00709,.01673,
.01132,.01673,
.01132,.01675,
.01132,.03445,
0.0*
%
%ADD47MACRO47*%
%ADD125R,.134X.134*%
%ADD105R,.038X.048*%
%ADD74R,.099X.033*%
%ADD35R,.033X.099*%
%ADD25R,.095X.056*%
%ADD162R,.244X.244*%
%ADD73R,.099X.08*%
%ADD48R,.08X.099*%
%ADD149R,.156X.156*%
%ADD141R,.228X.228*%
%ADD174R,.079X.059*%
%ADD49R,.059X.079*%
%ADD176C,.006*%
G75*
%LPD*%
G75*
G54D100*
X266383Y636830D03*
G54D101*
X270135Y702797D03*
Y696891D03*
X318288Y521500D03*
Y527406D03*
X324182Y521508D03*
Y527414D03*
X330182Y521508D03*
Y527414D03*
X336182Y521508D03*
Y527414D03*
X342182Y521508D03*
Y527414D03*
X354182Y521508D03*
Y527414D03*
X348182Y521508D03*
Y527414D03*
X360182Y521508D03*
Y527414D03*
X447440Y703203D03*
Y709109D03*
X453940Y703203D03*
X460940D03*
X453940Y709109D03*
X460940D03*
X467440Y703203D03*
X473940D03*
X480440D03*
X467440Y709109D03*
X473940D03*
X480440D03*
X551129Y280528D03*
X545223D03*
X635408Y511230D03*
X641314D03*
G54D110*
X329986Y465124D03*
Y467093D03*
Y469061D03*
Y471030D03*
Y472998D03*
Y474967D03*
Y476935D03*
Y478904D03*
Y480872D03*
Y482841D03*
Y484809D03*
Y486778D03*
X363844Y471030D03*
Y469061D03*
Y467093D03*
Y465124D03*
Y486778D03*
Y484809D03*
Y482841D03*
Y480872D03*
Y478904D03*
Y476935D03*
Y474967D03*
Y472998D03*
G54D120*
X413175Y525582D03*
Y527157D03*
Y528732D03*
Y530307D03*
Y531881D03*
Y533456D03*
Y535031D03*
Y536606D03*
X433057Y533456D03*
Y531881D03*
Y530307D03*
Y528732D03*
Y527157D03*
Y525582D03*
Y536606D03*
Y535031D03*
G54D102*
X290490Y473703D03*
X600696Y612943D03*
X610796Y611219D03*
G54D111*
X350411Y30188D03*
Y46920D03*
X358285Y30188D03*
X366159D03*
X358285Y46920D03*
X366159D03*
X374033Y30188D03*
X381907D03*
X374033Y46920D03*
X381907D03*
X389781Y30188D03*
X397655D03*
X389781Y46920D03*
X397655D03*
G54D112*
X352079Y382282D03*
X347079D03*
Y408896D03*
X352079D03*
X362079Y382282D03*
X357079D03*
Y408896D03*
X362079D03*
G54D130*
X451840Y639199D03*
Y641758D03*
Y644317D03*
Y646876D03*
Y649436D03*
Y651995D03*
Y654554D03*
Y657113D03*
Y661699D03*
Y664258D03*
Y666817D03*
Y669376D03*
Y671936D03*
Y674495D03*
Y677054D03*
Y679613D03*
X474840Y644317D03*
Y641758D03*
Y639199D03*
Y657113D03*
Y654554D03*
Y651995D03*
Y649436D03*
Y646876D03*
Y674495D03*
Y671936D03*
Y669376D03*
Y666817D03*
Y664258D03*
Y661699D03*
Y679613D03*
Y677054D03*
X600118Y115098D03*
Y117657D03*
Y120216D03*
Y122775D03*
Y125334D03*
Y127893D03*
Y130452D03*
Y133012D03*
Y135571D03*
Y138130D03*
Y140689D03*
Y143248D03*
Y145807D03*
Y148366D03*
X623118Y122775D03*
Y120216D03*
Y117657D03*
Y115098D03*
Y138130D03*
Y135571D03*
Y133012D03*
Y130452D03*
Y127893D03*
Y125334D03*
Y148366D03*
Y145807D03*
Y143248D03*
Y140689D03*
X627463Y675600D03*
Y678159D03*
Y680718D03*
Y683277D03*
Y685836D03*
Y688395D03*
Y690954D03*
Y693514D03*
Y696073D03*
Y698632D03*
Y701191D03*
Y703750D03*
Y706309D03*
Y708868D03*
X650463Y675600D03*
Y690954D03*
Y688395D03*
Y685836D03*
Y683277D03*
Y680718D03*
Y678159D03*
Y706309D03*
Y703750D03*
Y701191D03*
Y698632D03*
Y696073D03*
Y693514D03*
Y708868D03*
G54D121*
X428747Y455592D03*
Y477403D03*
G54D103*
X287709Y483619D03*
G54D10*
X-34986Y133213D03*
X-36758D03*
X-34986Y240533D03*
X-36758D03*
Y746493D03*
X-34986D03*
G54D131*
X481102Y34528D03*
G54D104*
X284428Y654034D03*
Y656002D03*
Y657971D03*
Y659939D03*
Y661908D03*
Y663876D03*
Y665845D03*
Y667813D03*
Y669782D03*
Y671750D03*
Y673719D03*
Y675688D03*
Y677656D03*
Y679624D03*
Y681593D03*
Y683562D03*
Y685530D03*
Y687499D03*
Y689467D03*
Y691436D03*
Y693404D03*
Y695373D03*
Y697341D03*
Y699310D03*
Y701278D03*
X345452Y659939D03*
Y657971D03*
Y656002D03*
Y654034D03*
Y675688D03*
Y673719D03*
Y671750D03*
Y669782D03*
Y667813D03*
Y665845D03*
Y663876D03*
Y661908D03*
Y691436D03*
Y689467D03*
Y687499D03*
Y685530D03*
Y683562D03*
Y681593D03*
Y679624D03*
Y677656D03*
Y701278D03*
Y699310D03*
Y697341D03*
Y695373D03*
Y693404D03*
X510928Y650034D03*
Y652002D03*
Y653971D03*
Y655939D03*
Y657908D03*
Y659876D03*
Y661845D03*
Y663813D03*
Y665782D03*
Y667750D03*
Y669719D03*
Y671688D03*
Y673656D03*
Y675624D03*
Y677593D03*
Y679562D03*
Y681530D03*
Y683499D03*
Y685467D03*
Y687436D03*
Y689404D03*
Y691373D03*
Y693341D03*
Y695310D03*
Y697278D03*
X571952Y659876D03*
Y657908D03*
Y655939D03*
Y653971D03*
Y652002D03*
Y650034D03*
Y675624D03*
Y673656D03*
Y671688D03*
Y669719D03*
Y667750D03*
Y665782D03*
Y663813D03*
Y661845D03*
Y691373D03*
Y689404D03*
Y687436D03*
Y685467D03*
Y683499D03*
Y681530D03*
Y679562D03*
Y677593D03*
Y697278D03*
Y695310D03*
Y693341D03*
G54D113*
X384758Y645239D03*
Y647739D03*
Y650239D03*
Y652739D03*
Y655239D03*
Y657739D03*
Y660239D03*
Y662739D03*
Y667942D03*
Y670442D03*
Y672942D03*
Y675442D03*
Y677942D03*
Y680442D03*
Y682942D03*
Y685442D03*
X406358Y660239D03*
Y657739D03*
Y655239D03*
Y652739D03*
Y650239D03*
Y647739D03*
Y645239D03*
Y662739D03*
Y675442D03*
Y672942D03*
Y670442D03*
Y667942D03*
Y685442D03*
Y682942D03*
Y680442D03*
Y677942D03*
G54D122*
X428747Y458694D03*
Y474305D03*
G54D11*
X10859Y109561D03*
X73740Y20708D03*
X703661D03*
G54D20*
X36024Y187233D03*
Y181225D03*
Y205257D03*
Y199249D03*
Y193241D03*
Y217272D03*
Y211264D03*
X41930Y178221D03*
Y202253D03*
Y196245D03*
Y190237D03*
Y220276D03*
Y214268D03*
Y208260D03*
G54D140*
X525802Y448680D03*
X524227D03*
X522653D03*
X521078D03*
X519503D03*
X517928D03*
X516353D03*
X514779D03*
X513204D03*
Y476632D03*
X514779D03*
X516353D03*
X517928D03*
X519503D03*
X521078D03*
X522653D03*
X524227D03*
X525802D03*
X533676Y448680D03*
X532101D03*
X530527D03*
X528952D03*
X527377D03*
Y476632D03*
X528952D03*
X530527D03*
X532101D03*
X533676D03*
G54D141*
X523440Y462656D03*
G54D105*
X306809Y390104D03*
Y381443D03*
X299919D03*
Y390104D03*
G54D114*
X385118Y691156D03*
Y696156D03*
Y701156D03*
Y706156D03*
X405918Y691156D03*
Y706156D03*
Y701156D03*
Y696156D03*
X493954Y250584D03*
Y255584D03*
Y260584D03*
Y265584D03*
X522588Y250584D03*
Y265584D03*
Y260584D03*
Y255584D03*
X559199Y601204D03*
Y606204D03*
Y611204D03*
Y616204D03*
X579999Y611204D03*
Y606204D03*
Y601204D03*
Y616204D03*
X613640Y339818D03*
Y344818D03*
Y349818D03*
Y354818D03*
X620131Y645072D03*
Y650072D03*
Y655072D03*
Y660072D03*
X634440Y344818D03*
Y339818D03*
Y354818D03*
Y349818D03*
X640931Y660072D03*
Y655072D03*
Y650072D03*
Y645072D03*
G54D30*
X59920Y170026D03*
X65696Y170071D03*
X59920Y175826D03*
X65696Y175871D03*
X59821Y193765D03*
Y199565D03*
X65821D03*
Y193765D03*
X60242Y212743D03*
Y218543D03*
X66242D03*
Y212743D03*
X71880Y195309D03*
Y201109D03*
X77368Y295057D03*
Y289257D03*
X116165Y562839D03*
Y568639D03*
X124628Y726984D03*
Y732784D03*
X141699Y25494D03*
Y31294D03*
X151101Y455287D03*
Y449487D03*
X292893Y72444D03*
Y66644D03*
X298293Y72444D03*
Y66644D03*
X303693Y72444D03*
Y66644D03*
X367531Y641507D03*
Y635707D03*
X416288Y512677D03*
Y506877D03*
X421788Y512677D03*
Y506877D03*
X438258Y548889D03*
Y543089D03*
X454641Y518021D03*
Y523821D03*
X542248Y97186D03*
Y102986D03*
X547340Y473756D03*
Y479556D03*
X560938Y106523D03*
Y100723D03*
X562340Y475256D03*
Y481056D03*
X585805Y201406D03*
Y207206D03*
X718231Y568773D03*
Y574573D03*
G54D123*
X426950Y492873D03*
G54D21*
X47220Y28062D03*
X43480D03*
X39740D03*
Y37708D03*
X47220D03*
X424700Y661479D03*
X432180D03*
Y651833D03*
X428440D03*
X424700D03*
G54D132*
X478370Y104470D03*
Y113070D03*
G54D150*
X590999Y69167D03*
Y77041D03*
Y84915D03*
X615657Y69167D03*
Y77041D03*
Y84915D03*
G54D12*
X20859Y109561D03*
X83740Y20708D03*
X78740Y30708D03*
X507489Y360278D03*
X713661Y20708D03*
X708661Y30708D03*
G54D40*
X70066Y560821D03*
X70220Y552972D03*
X70066Y576821D03*
Y568821D03*
X84989Y542702D03*
X77546Y560821D03*
X77700Y552972D03*
X77546Y576821D03*
Y568821D03*
X97605Y435943D03*
X90125D03*
X97605Y426943D03*
X90125D03*
X97627Y444943D03*
X90147D03*
X102240Y542702D03*
X92469D03*
X109720D03*
X240130Y418256D03*
X232650D03*
X240195Y434135D03*
X232715D03*
X240195Y426135D03*
X232715D03*
X250678Y608063D03*
X258158D03*
X250703Y623716D03*
X258183D03*
X250678Y615871D03*
X258158D03*
X313297Y546404D03*
X320777D03*
X321848Y571803D03*
X335123Y10530D03*
X327643D03*
X335123Y26530D03*
X327643D03*
X335123Y18530D03*
X327643D03*
X329328Y571803D03*
X351910Y331176D03*
X344430D03*
X343632Y613013D03*
X351112D03*
X343632Y605013D03*
X351112D03*
X343632Y621013D03*
X351112D03*
X417881Y412830D03*
X410401D03*
X417881Y420830D03*
X410401D03*
X417881Y436830D03*
X410401D03*
X417881Y428830D03*
X410401D03*
X417881Y444830D03*
X410401D03*
X410551Y452830D03*
X403071D03*
X410551Y460574D03*
X403071D03*
X409942Y631847D03*
X417422D03*
X463867Y587570D03*
X456387D03*
X555998Y222533D03*
X563478D03*
X617872Y526967D03*
X610392D03*
X638602Y317360D03*
X638592Y324998D03*
X646082Y317360D03*
X646072Y324998D03*
X669690Y193115D03*
X666118Y304444D03*
X658638D03*
X677170Y193115D03*
X695683Y562356D03*
X695668Y578380D03*
Y570380D03*
Y586380D03*
X710585Y543908D03*
X703105D03*
X703163Y562356D03*
X703148Y578380D03*
Y570380D03*
Y586380D03*
X757490Y105176D03*
X750010D03*
X758937Y577664D03*
X758928Y585787D03*
X766417Y577664D03*
X766408Y585787D03*
G54D106*
X305097Y647144D03*
X303129D03*
X301160D03*
X299192D03*
X297223D03*
X295255D03*
X293286D03*
X291318D03*
Y708168D03*
X293286D03*
X295255D03*
X297223D03*
X299192D03*
X301160D03*
X303129D03*
X305097D03*
X320846Y647144D03*
X318877D03*
X316908D03*
X314940D03*
X312972D03*
X311003D03*
X309034D03*
X307066D03*
Y708168D03*
X309034D03*
X311003D03*
X312972D03*
X314940D03*
X316908D03*
X318877D03*
X320846D03*
X336594Y647144D03*
X334625D03*
X332657D03*
X330688D03*
X328720D03*
X326751D03*
X324783D03*
X322814D03*
Y708168D03*
X324783D03*
X326751D03*
X328720D03*
X330688D03*
X332657D03*
X334625D03*
X336594D03*
X338562Y647144D03*
Y708168D03*
X525692Y643144D03*
X523723D03*
X521755D03*
X519786D03*
X517818D03*
Y704168D03*
X519786D03*
X521755D03*
X523723D03*
X525692D03*
X541440Y643144D03*
X539472D03*
X537503D03*
X535534D03*
X533566D03*
X531597D03*
X529629D03*
X527660D03*
Y704168D03*
X529629D03*
X531597D03*
X533566D03*
X535534D03*
X537503D03*
X539472D03*
X541440D03*
X557188Y643144D03*
X555220D03*
X553251D03*
X551283D03*
X549314D03*
X547346D03*
X545377D03*
X543408D03*
Y704168D03*
X545377D03*
X547346D03*
X549314D03*
X551283D03*
X553251D03*
X555220D03*
X557188D03*
X565062Y643144D03*
X563094D03*
X561125D03*
X559157D03*
Y704168D03*
X561125D03*
X563094D03*
X565062D03*
G54D142*
X519985Y526639D03*
X525085Y522183D03*
G54D133*
X482093Y127519D03*
Y129487D03*
Y131456D03*
Y133424D03*
Y135393D03*
Y137361D03*
Y139330D03*
Y141298D03*
Y143267D03*
Y145235D03*
Y147204D03*
Y149172D03*
Y151141D03*
Y153109D03*
Y155078D03*
Y157046D03*
Y159015D03*
Y160983D03*
Y162952D03*
Y164920D03*
Y166889D03*
Y168857D03*
Y170826D03*
Y172794D03*
Y174763D03*
Y176731D03*
X573117Y139330D03*
Y137361D03*
Y135393D03*
Y133424D03*
Y131456D03*
Y129487D03*
Y127519D03*
Y155078D03*
Y153109D03*
Y151141D03*
Y149172D03*
Y147204D03*
Y145235D03*
Y143267D03*
Y141298D03*
Y170826D03*
Y168857D03*
Y166889D03*
Y164920D03*
Y162952D03*
Y160983D03*
Y159015D03*
Y157046D03*
Y176731D03*
Y174763D03*
Y172794D03*
G54D31*
X65684Y233920D03*
X65974Y247944D03*
X76210Y163577D03*
X85010Y167577D03*
Y159577D03*
X77944Y181967D03*
X86744Y185967D03*
Y177967D03*
X77944Y195733D03*
X86744Y199733D03*
Y191733D03*
X81873Y209852D03*
X74484Y229920D03*
X81933Y223734D03*
X74484Y237920D03*
X74774Y251944D03*
Y243944D03*
X90733Y219734D03*
X90673Y213852D03*
Y205852D03*
X90733Y227734D03*
X133447Y667464D03*
Y675464D03*
X144203Y15162D03*
X135403Y11162D03*
Y19162D03*
X142247Y671464D03*
X179419Y667816D03*
X170619Y663816D03*
Y671816D03*
X425881Y631477D03*
X434681Y627477D03*
Y635477D03*
X491413Y214434D03*
X482613Y210434D03*
Y218434D03*
X746023Y450832D03*
X737223Y446832D03*
Y454832D03*
G54D115*
X395227Y633135D03*
Y640615D03*
X403101Y636875D03*
X535735Y259622D03*
Y267102D03*
X543609Y263362D03*
G54D13*
X23628Y321764D03*
Y338300D03*
X45282Y321764D03*
G54D151*
X590999Y92789D03*
X615657D03*
G54D124*
X428628Y521153D03*
X427053D03*
X425478D03*
X423903D03*
X422329D03*
X420754D03*
X419179D03*
X417604D03*
Y541035D03*
X419179D03*
X420754D03*
X422329D03*
X423903D03*
X425478D03*
X427053D03*
X428628D03*
G54D160*
X642721Y384787D03*
Y409983D03*
X674155Y384787D03*
Y409983D03*
G54D22*
X40749Y150808D03*
Y249194D03*
G54D125*
X423116Y531094D03*
G54D50*
X101399Y204167D03*
X98840D03*
Y218734D03*
X101399D03*
X106517Y204167D03*
X103958D03*
X106517Y218734D03*
X103958D03*
G54D14*
X19987Y374226D03*
Y391942D03*
X32250Y374226D03*
Y391942D03*
G54D170*
X711575Y143555D03*
Y195355D03*
Y222361D03*
Y274161D03*
X733975Y143555D03*
Y195355D03*
Y222361D03*
Y274161D03*
G54D41*
X68489Y603914D03*
Y608914D03*
Y613914D03*
Y623914D03*
Y628914D03*
Y618914D03*
Y633914D03*
Y638914D03*
Y643914D03*
Y653914D03*
Y658914D03*
Y648914D03*
X103725Y603914D03*
Y608914D03*
Y613914D03*
Y623914D03*
Y628914D03*
Y618914D03*
Y633914D03*
Y638914D03*
Y643914D03*
Y653914D03*
Y658914D03*
Y648914D03*
G54D134*
X495125Y118424D03*
X493156D03*
X491188D03*
Y185826D03*
X493156D03*
X495125D03*
X510873Y118424D03*
X508904D03*
X506936D03*
X504967D03*
X502999D03*
X501030D03*
X499062D03*
X497093D03*
Y185826D03*
X499062D03*
X501030D03*
X502999D03*
X504967D03*
X506936D03*
X508904D03*
X510873D03*
X526621Y118424D03*
X524652D03*
X522684D03*
X520715D03*
X518747D03*
X516778D03*
X514810D03*
X512841D03*
Y185826D03*
X514810D03*
X516778D03*
X518747D03*
X520715D03*
X522684D03*
X524652D03*
X526621D03*
X542369Y118424D03*
X540400D03*
X538432D03*
X536463D03*
X534495D03*
X532526D03*
X530558D03*
X528589D03*
Y185826D03*
X530558D03*
X532526D03*
X534495D03*
X536463D03*
X538432D03*
X540400D03*
X542369D03*
X558117Y118424D03*
X556148D03*
X554180D03*
X552211D03*
X550243D03*
X548274D03*
X546306D03*
X544337D03*
Y185826D03*
X546306D03*
X548274D03*
X550243D03*
X552211D03*
X554180D03*
X556148D03*
X558117D03*
X564022Y118424D03*
X562054D03*
X560085D03*
Y185826D03*
X562054D03*
X564022D03*
G54D116*
X399337Y716398D03*
Y713839D03*
Y711280D03*
X391857D03*
Y713839D03*
Y716398D03*
G54D107*
X310327Y609214D03*
X402920Y609350D03*
G54D143*
X554780Y38803D03*
X617371D03*
X679963D03*
G54D23*
X41930Y184229D03*
G54D161*
X643071Y386361D03*
Y387936D03*
Y389511D03*
Y391086D03*
Y392661D03*
Y394235D03*
Y395810D03*
Y397385D03*
Y398960D03*
Y400535D03*
Y402109D03*
Y403684D03*
Y405259D03*
Y406834D03*
Y408409D03*
X673805Y391086D03*
Y389511D03*
Y387936D03*
Y386361D03*
Y406834D03*
Y405259D03*
Y403684D03*
Y402109D03*
Y400535D03*
Y398960D03*
Y397385D03*
Y395810D03*
Y394235D03*
Y392661D03*
Y408409D03*
G54D152*
X584166Y276414D03*
X591774Y284989D03*
G54D32*
X57994Y278657D03*
X73742D03*
G54D162*
X658438Y397385D03*
G54D15*
X20435Y561223D03*
X17876D03*
X15317D03*
X12758D03*
Y584223D03*
X15317D03*
X17876D03*
X20435D03*
X20507Y622914D03*
X17948D03*
X15389D03*
X12830D03*
X10271D03*
Y645914D03*
X12830D03*
X15389D03*
X17948D03*
X20507D03*
X36567Y79540D03*
X34008D03*
X31449D03*
Y102540D03*
X34008D03*
X36567D03*
X38349Y561223D03*
X35790D03*
X33231D03*
X30672D03*
X28112D03*
X25553D03*
X22994D03*
Y584223D03*
X25553D03*
X28112D03*
X30672D03*
X33231D03*
X35790D03*
X38349D03*
X38421Y622914D03*
X35862D03*
X33303D03*
X30744D03*
X28185D03*
X25625D03*
X23066D03*
Y645914D03*
X25625D03*
X28185D03*
X30744D03*
X33303D03*
X35862D03*
X38421D03*
X51922Y79540D03*
X49363D03*
X46803D03*
X44244D03*
X41685D03*
X39126D03*
Y102540D03*
X41685D03*
X44244D03*
X46803D03*
X49363D03*
X51922D03*
X46026Y561223D03*
X43467D03*
X40908D03*
Y584223D03*
X43467D03*
X46026D03*
X43539Y622914D03*
X40980D03*
Y645914D03*
X43539D03*
X64717Y79540D03*
X62158D03*
X59599D03*
X57040D03*
X54481D03*
Y102540D03*
X57040D03*
X59599D03*
X62158D03*
X64717D03*
G54D33*
X58466Y293171D03*
X66892D03*
X83475Y279475D03*
X95060Y159811D03*
X91320Y167685D03*
X98800D03*
X87215Y271601D03*
X90955Y279475D03*
X142500Y460406D03*
X138760Y468280D03*
X146240D03*
X146364Y726705D03*
X150104Y734579D03*
X153844Y726705D03*
X238069Y633421D03*
X234329Y641295D03*
X241809D03*
X258553Y438319D03*
X254813Y430445D03*
X262293D03*
X321514Y415629D03*
X325254Y407755D03*
X328994Y415629D03*
X369934Y326749D03*
X377414D03*
X373674Y334623D03*
X698881Y529230D03*
X716021Y521256D03*
X712281Y529130D03*
X702621Y521356D03*
X706361Y529230D03*
X719761Y529130D03*
G54D108*
X332490Y328505D03*
Y338347D03*
X695230Y201790D03*
Y190373D03*
X748713Y125542D03*
Y114125D03*
G54D117*
X412330Y243725D03*
Y245694D03*
Y247662D03*
Y249631D03*
Y251599D03*
Y253569D03*
Y255537D03*
Y257505D03*
Y259473D03*
Y261442D03*
Y263410D03*
Y265379D03*
Y267347D03*
Y269316D03*
Y271284D03*
Y273253D03*
Y275222D03*
Y277190D03*
Y279158D03*
Y281127D03*
Y283095D03*
Y285064D03*
Y287032D03*
Y289001D03*
Y290969D03*
Y292938D03*
Y294906D03*
Y296875D03*
Y298843D03*
Y300812D03*
X434882Y243725D03*
Y245694D03*
Y247662D03*
Y249631D03*
Y251599D03*
Y253569D03*
Y255537D03*
Y257505D03*
Y259473D03*
Y261442D03*
Y263410D03*
Y265379D03*
Y267347D03*
Y269316D03*
Y271284D03*
Y273253D03*
Y275222D03*
Y277190D03*
Y279158D03*
Y281127D03*
Y283095D03*
Y285064D03*
Y287032D03*
Y289001D03*
Y290969D03*
Y292938D03*
Y294906D03*
Y296875D03*
Y298843D03*
Y300812D03*
G54D126*
X431340Y599929D03*
X435080Y592055D03*
X438820Y599929D03*
X474860Y581398D03*
X471120Y589272D03*
X478600D03*
G54D24*
X45282Y338300D03*
G54D144*
X546181Y81889D03*
G54D171*
X712975Y155655D03*
Y165455D03*
Y173455D03*
Y183255D03*
Y234461D03*
Y244261D03*
Y252261D03*
Y262061D03*
X723275Y165455D03*
Y173455D03*
Y183255D03*
Y244261D03*
Y252261D03*
Y262061D03*
G54D51*
X97150Y553052D03*
G54D60*
X148357Y34404D03*
X146782D03*
Y46710D03*
X148357D03*
X153082Y34404D03*
X151507D03*
X149932D03*
X153082Y46710D03*
X151507D03*
X149932D03*
X416029Y521083D03*
Y541105D03*
X430203Y521083D03*
Y541105D03*
G54D135*
X495228Y540849D03*
Y542423D03*
Y543998D03*
Y545573D03*
Y547148D03*
Y548723D03*
Y550297D03*
Y551872D03*
Y553447D03*
Y555022D03*
Y556597D03*
Y558171D03*
Y559746D03*
Y561321D03*
Y562896D03*
Y564471D03*
Y566045D03*
Y567620D03*
Y569195D03*
Y570770D03*
Y572345D03*
Y573919D03*
Y575494D03*
Y577069D03*
Y578644D03*
Y580219D03*
Y581793D03*
Y583368D03*
Y584943D03*
Y586518D03*
Y588093D03*
Y589667D03*
X556252Y548723D03*
Y547148D03*
Y545573D03*
Y543998D03*
Y542423D03*
Y540849D03*
Y564471D03*
Y562896D03*
Y561321D03*
Y559746D03*
Y558171D03*
Y556597D03*
Y555022D03*
Y553447D03*
Y551872D03*
Y550297D03*
Y580219D03*
Y578644D03*
Y577069D03*
Y575494D03*
Y573919D03*
Y572345D03*
Y570770D03*
Y569195D03*
Y567620D03*
Y566045D03*
Y589667D03*
Y588093D03*
Y586518D03*
Y584943D03*
Y583368D03*
Y581793D03*
G54D42*
X65740Y717159D03*
X67450Y727094D03*
X72170Y696299D03*
X70460Y707975D03*
X691990Y610622D03*
X684570Y615002D03*
G54D153*
X595427Y501238D03*
Y516986D03*
X622199Y501238D03*
Y516986D03*
X632769Y527813D03*
Y543561D03*
X659541Y527813D03*
Y543561D03*
G54D25*
X44279Y374032D03*
Y392536D03*
X162364Y720437D03*
Y738941D03*
G54D127*
X447355Y157140D03*
Y177140D03*
X461921Y157140D03*
Y177140D03*
G54D70*
X164993Y705542D03*
Y700542D03*
Y695542D03*
Y710542D03*
X662460Y149432D03*
Y145496D03*
X662673Y164035D03*
Y160099D03*
X662294Y228238D03*
Y224302D03*
X662908Y242841D03*
Y238905D03*
X673484Y149432D03*
Y145496D03*
X673697Y164035D03*
Y160099D03*
X673318Y228238D03*
Y224302D03*
X673932Y242841D03*
Y238905D03*
G54D16*
X13820Y597179D03*
X9820Y605979D03*
X17820D03*
X70796Y258779D03*
X66796Y267579D03*
X74796D03*
X97449Y181016D03*
X93449Y189816D03*
X101449D03*
X175180Y688329D03*
X179180Y679529D03*
X171180D03*
X175689Y715673D03*
X171689Y724473D03*
X179689D03*
X187440Y699556D03*
X183440Y708356D03*
X191440D03*
X197440D03*
X201440Y699556D03*
X205440Y708356D03*
X211440D03*
X215440Y699556D03*
X219440Y708356D03*
X225940D03*
X229940Y699556D03*
X233940Y708356D03*
X244440Y699556D03*
X240440Y708356D03*
X248440D03*
X258940Y699556D03*
X254940Y708356D03*
X262940D03*
X353298Y638032D03*
X357298Y629232D03*
X361298Y638032D03*
X381218Y629998D03*
X373218D03*
X377218Y638798D03*
X430315Y611073D03*
X426315Y619873D03*
X444135Y611073D03*
X440135Y619873D03*
X448135D03*
X434315D03*
X465165Y595260D03*
X457935Y611073D03*
X461165Y604060D03*
X453935Y619873D03*
X461935D03*
X475795Y281667D03*
X479795Y272867D03*
X471795D03*
X479648Y612832D03*
X469165Y604060D03*
X479832Y628841D03*
X483648Y604032D03*
X487648Y612832D03*
X494282Y628836D03*
X483832Y620041D03*
X487832Y628841D03*
X498282Y620036D03*
X502282Y628836D03*
X512238Y620174D03*
X508238Y628974D03*
X526278Y629595D03*
X522278Y620795D03*
X516238Y628974D03*
X530278Y620795D03*
G54D43*
X76880Y143269D03*
X739968Y29361D03*
G54D136*
X507489Y281538D03*
G54D61*
X149932Y40557D03*
G54D118*
X412699Y466933D03*
X408369D03*
X412448Y471896D03*
Y476226D03*
G54D154*
X605796Y165160D03*
X609733Y215672D03*
G54D34*
X71970Y357848D03*
X105613Y147532D03*
X147590Y647878D03*
X487770Y513674D03*
X577880Y395242D03*
X693400Y758198D03*
X745580Y62870D03*
G54D109*
X336088Y459022D03*
Y492880D03*
X351836Y459022D03*
X349868D03*
X347899D03*
X345931D03*
X343962D03*
X341994D03*
X340025D03*
X338057D03*
Y492880D03*
X340025D03*
X341994D03*
X343962D03*
X345931D03*
X347899D03*
X349868D03*
X351836D03*
X357742Y459022D03*
X355773D03*
X353805D03*
Y492880D03*
X355773D03*
X357742D03*
G54D52*
X120635Y499230D03*
X330425Y556306D03*
X375349Y530269D03*
G54D145*
X556181Y81889D03*
G54D172*
X732284Y109187D03*
Y126509D03*
G54D163*
X665457Y209073D03*
X682779D03*
G54D35*
X67640Y493618D03*
G54D164*
X658936Y359552D03*
X673897D03*
G54D71*
X176939Y29820D03*
X174380D03*
X171820D03*
X169261D03*
Y46284D03*
G54D17*
X12178Y612129D03*
X9028D03*
X20020Y658951D03*
X31260Y30414D03*
X34410D03*
Y26414D03*
X31260D03*
X38807Y547034D03*
X37197Y597285D03*
X28105Y595792D03*
X24955D03*
X36937Y608125D03*
X35960Y658951D03*
X32810D03*
X23170D03*
X45355Y14588D03*
X42205D03*
X45355Y18588D03*
X42205D03*
X49817Y494570D03*
X52967D03*
X51325Y518072D03*
X48175D03*
X41957Y547034D03*
X44507Y597285D03*
X47657D03*
X40347D03*
X40087Y608125D03*
X53751Y643928D03*
X40317Y658951D03*
X43467D03*
X53751Y648428D03*
X58654Y115158D03*
X61804D03*
X69485Y188946D03*
X60663Y189182D03*
X63813D03*
X57029Y257049D03*
X60179D03*
X66533Y526417D03*
X63383D03*
Y530417D03*
X66533D03*
X58108Y619407D03*
X54958D03*
X58108Y614907D03*
X54958D03*
X56901Y643928D03*
Y648428D03*
X77895Y172605D03*
X74745D03*
X72635Y188946D03*
X85460Y232861D03*
X82310D03*
X80074Y389621D03*
X76924D03*
X80074Y385722D03*
X76924D03*
X80094Y393857D03*
X76944D03*
X80094Y397913D03*
X76944D03*
X79235Y513104D03*
X76085D03*
X79235Y517104D03*
X76085D03*
Y521104D03*
X79235D03*
X99318Y225836D03*
X96168D03*
X95807Y420074D03*
X92657D03*
X110624Y392023D03*
X113774D03*
X110624Y387978D03*
X113774D03*
X109393Y406383D03*
X106243D03*
X132164Y418152D03*
X129014D03*
X132178Y422320D03*
X129028D03*
X129701Y462738D03*
X132851D03*
X129701Y470738D03*
X132851D03*
X129701Y466738D03*
X132851D03*
Y458733D03*
X129701D03*
X118830Y513831D03*
X121980D03*
X121847Y523033D03*
X118697D03*
X121880Y519031D03*
X118730D03*
X124467Y675871D03*
X127617D03*
Y670879D03*
X124467D03*
X120953Y665638D03*
X124103D03*
X129184Y729750D03*
X132334D03*
X129184Y725250D03*
X132334D03*
X137232Y43439D03*
X134082D03*
X134086Y39191D03*
X137236D03*
X134151Y47370D03*
X137301D03*
X143677Y76588D03*
X140527D03*
X133539D03*
X136689D03*
X144701Y296735D03*
X141551D03*
X142943Y284987D03*
X146093D03*
X142943Y288987D03*
X146093D03*
Y292987D03*
X142943D03*
X141262Y300625D03*
X144412D03*
X138857Y310543D03*
X142007D03*
X139238Y327933D03*
X142388D03*
X138857Y323543D03*
X142007D03*
X138857Y319043D03*
X142007D03*
X138857Y314543D03*
X142007D03*
X139381Y332046D03*
X142531D03*
X144660Y407428D03*
X141510D03*
X144660Y411428D03*
X141510D03*
X136852Y513804D03*
X133702D03*
X137177Y738726D03*
X140327D03*
X137278Y725173D03*
X140428D03*
X137177Y730726D03*
X140327D03*
X137177Y734726D03*
X140327D03*
X137177Y742726D03*
X140327D03*
X153937Y12151D03*
X150787D03*
X150713Y17718D03*
X153863D03*
X153139Y55906D03*
X156289D03*
X152553Y74863D03*
X149403D03*
X164447Y432521D03*
X164245Y436834D03*
X164774Y441077D03*
Y445034D03*
X167597Y432521D03*
X167395Y436834D03*
X167924Y441077D03*
X173095Y444739D03*
X176245D03*
X167924Y445034D03*
X172654Y477790D03*
X175804D03*
X177038Y643933D03*
X173888D03*
X166388D03*
X169538D03*
X175619Y705976D03*
X172469D03*
X175619Y701976D03*
X172469D03*
X175619Y697976D03*
X172469D03*
X178289Y694040D03*
X175139D03*
X175619Y709976D03*
X172469D03*
X180078Y730521D03*
X176928D03*
X188261Y418925D03*
X185111D03*
X185117Y414885D03*
X188267D03*
X189173Y444392D03*
X186023D03*
X191163Y672526D03*
X194313D03*
X184312Y693887D03*
X187462D03*
X201995Y373701D03*
X198845D03*
X203584Y469953D03*
X200434D03*
Y474253D03*
X203584D03*
X207178Y576893D03*
X204028D03*
X207178Y572893D03*
X204028D03*
Y580893D03*
X207178D03*
Y584893D03*
X204028D03*
Y588893D03*
X207178D03*
X209299Y621977D03*
Y625977D03*
Y629977D03*
Y637977D03*
Y633977D03*
X208882Y671772D03*
X205732D03*
X212378Y596957D03*
X215528D03*
X212378Y600957D03*
X215528D03*
X212449Y621977D03*
Y625977D03*
Y629977D03*
Y637977D03*
Y633977D03*
X219229Y671772D03*
X222379D03*
X242631Y387964D03*
X238077Y439936D03*
X234927D03*
X233017Y671672D03*
X236167D03*
X245781Y387964D03*
X258477Y443592D03*
X255327D03*
X246816Y583156D03*
X243666D03*
X246816Y587156D03*
X243666D03*
X249349Y596382D03*
X246199D03*
X253796Y602262D03*
X256946D03*
X246475Y671772D03*
X249625D03*
X258991Y693945D03*
X255841D03*
X260110Y24932D03*
X263260D03*
X259673Y29229D03*
X262823D03*
X263352Y33472D03*
X260202D03*
X268483Y37453D03*
X271633D03*
X263352Y37429D03*
X260202D03*
X261754Y390871D03*
X264904D03*
X274625Y403203D03*
Y394703D03*
Y399203D03*
X273051Y656491D03*
Y652214D03*
Y648117D03*
Y664156D03*
X259895Y671772D03*
X263045D03*
X273051Y691038D03*
X285703Y6670D03*
X282553D03*
X278653Y6636D03*
X275503D03*
X284601Y36787D03*
X281451D03*
X277775Y403203D03*
Y394703D03*
Y399203D03*
X276201Y656491D03*
Y652214D03*
Y648117D03*
Y664156D03*
Y691038D03*
X285666Y717269D03*
X282516D03*
X301187Y398429D03*
X304337D03*
X294430Y471932D03*
X297580D03*
X294389Y476239D03*
X297539D03*
X301700Y597806D03*
X304850D03*
X302036Y623877D03*
X305186D03*
X300799Y717212D03*
X303949D03*
X296717Y721080D03*
X299867D03*
X316473Y295851D03*
X313323D03*
X313324Y303888D03*
X316474D03*
X313173Y307843D03*
X316323D03*
X316585Y299946D03*
X313435D03*
X319225Y326386D03*
X316075D03*
X316392Y338320D03*
X313242D03*
Y342418D03*
X316392D03*
Y354376D03*
X313242D03*
X316392Y358376D03*
X313242D03*
Y350376D03*
X316392D03*
X313242Y346376D03*
X316392D03*
X311015Y362506D03*
X314165D03*
X320130Y380571D03*
X316980D03*
X316963Y463789D03*
X320113D03*
X320106Y475619D03*
X316956D03*
X315513Y563003D03*
X318663D03*
X316957Y556488D03*
X320107D03*
X316957Y552188D03*
X320107D03*
X312065Y597255D03*
X315215D03*
X333005Y32331D03*
X329855D03*
X327058Y353801D03*
X330208D03*
X327008Y349221D03*
X330158D03*
X322599Y421643D03*
X325749D03*
Y429583D03*
X322599D03*
X325749Y425585D03*
X322599D03*
X322949Y597198D03*
X326099D03*
X326723Y609480D03*
X323573D03*
X322949Y601121D03*
X326099D03*
X326628Y605364D03*
X323478D03*
X352578Y69305D03*
X346795Y299266D03*
X343645D03*
X342699Y312712D03*
X345849D03*
X343376Y308727D03*
X346526D03*
X345571Y322472D03*
X342421D03*
X339537Y424850D03*
X342687D03*
X351032Y424560D03*
X345750Y599212D03*
X348900D03*
X353667Y644166D03*
X366175Y15721D03*
X363025D03*
X355728Y69305D03*
X368743Y370508D03*
X354182Y424560D03*
X369484Y543467D03*
X356817Y644166D03*
X359105Y659130D03*
X355955D03*
X359103Y675130D03*
X355953D03*
X359105Y663128D03*
X355955D03*
X359085Y690624D03*
X355935D03*
X359103Y679133D03*
X355953D03*
X355955Y707128D03*
X359105D03*
Y703128D03*
X355955D03*
X359105Y699128D03*
X355955D03*
X359112Y695128D03*
X355962D03*
X360246Y723537D03*
X357096D03*
X359105Y711128D03*
X355955D03*
X369428Y723622D03*
X369336Y731459D03*
X357096Y735537D03*
X360246D03*
Y727537D03*
X357096D03*
X369336Y727459D03*
Y735459D03*
X360246Y739537D03*
X357096D03*
X369336Y739459D03*
X360246Y743537D03*
X357096D03*
X369336Y743459D03*
X374033Y17789D03*
X377183D03*
X371893Y370508D03*
X378061Y467075D03*
X374911D03*
X372634Y543467D03*
X376036Y547579D03*
X372886D03*
X376036Y551579D03*
X372886D03*
X370344Y658121D03*
X373494D03*
X370359Y654157D03*
X373509D03*
X370283Y650156D03*
X373433D03*
X370283Y646156D03*
X373433D03*
X370283Y666156D03*
X373433D03*
X370283Y670156D03*
X373433D03*
X370283Y674214D03*
X373433D03*
X370283Y678222D03*
X373433D03*
X370283Y686248D03*
X373433D03*
X370283Y690248D03*
X373433D03*
X370283Y682248D03*
X373433D03*
X370283Y702248D03*
X373433D03*
X370283Y706248D03*
X373433D03*
X370283Y698248D03*
X373433D03*
X370283Y694248D03*
X373433D03*
X384500Y715442D03*
X372578Y723622D03*
X372486Y731459D03*
Y727459D03*
Y735459D03*
Y739459D03*
Y743459D03*
X385724Y17519D03*
X388874D03*
X392789D03*
X395939D03*
X400589Y69610D03*
X390221Y69643D03*
X393371D03*
X400154Y532016D03*
X400064Y528015D03*
X400026Y524091D03*
X400037Y536127D03*
X400237Y540127D03*
X394293Y597942D03*
X397443D03*
X394599Y624109D03*
X397749D03*
X397743Y628233D03*
X394593D03*
X387650Y715442D03*
X403739Y69610D03*
X403304Y532016D03*
X403214Y528015D03*
X403176Y524091D03*
X416011Y550342D03*
X403187Y536127D03*
X403387Y540127D03*
X405831Y554402D03*
X408981D03*
X416040Y559017D03*
X416022Y554393D03*
X410348Y597288D03*
X407198D03*
X415542Y597300D03*
X416071Y609542D03*
X415542Y601257D03*
X416071Y605500D03*
X408163Y640872D03*
X411313D03*
X416504Y644754D03*
X416419Y652732D03*
Y656883D03*
Y648699D03*
Y673094D03*
Y669027D03*
Y677128D03*
Y681122D03*
X406646Y713835D03*
X403496D03*
X428204Y507319D03*
X431354D03*
X431006Y511581D03*
X427856D03*
X419161Y550342D03*
X419190Y559017D03*
X419172Y554393D03*
X424324Y566125D03*
X427474D03*
X431417Y587579D03*
X418692Y597300D03*
X419221Y609542D03*
X418692Y601257D03*
X425151Y604520D03*
X428301D03*
X432169D03*
X419221Y605500D03*
X428311Y640680D03*
X425161D03*
X419654Y644754D03*
X426270Y646100D03*
X429420D03*
X419569Y652732D03*
Y656883D03*
Y648699D03*
Y673094D03*
Y669027D03*
X422935Y685427D03*
X426085D03*
X419569Y677128D03*
Y681122D03*
X417427Y704664D03*
X420577D03*
Y696713D03*
X417427D03*
X420577Y700669D03*
X417427D03*
X447026Y184438D03*
X447760Y249404D03*
X447426Y245162D03*
Y241162D03*
Y237162D03*
X445190Y526518D03*
X448340D03*
X436290Y553337D03*
X439440D03*
X434567Y587579D03*
X435319Y604520D03*
X440040Y605071D03*
X443190D03*
X439642Y642843D03*
X442792D03*
X438863Y655595D03*
X442013D03*
Y651595D03*
X438863D03*
X439636Y646871D03*
X442786D03*
X442015Y667628D03*
X438865D03*
X442015Y671628D03*
X438865D03*
X442015Y675628D03*
X438865D03*
X442015Y679628D03*
X438865D03*
X461617Y74997D03*
X454582Y74774D03*
X457732D03*
X454433Y69194D03*
X457583D03*
X461791Y102736D03*
X458641D03*
X450176Y184438D03*
X450910Y249404D03*
X460351Y249696D03*
X457201D03*
X450576Y245162D03*
Y241162D03*
Y237162D03*
X450184Y257495D03*
X453334D03*
X456045Y513410D03*
X452895D03*
X452841Y532359D03*
X449691D03*
X449692Y538085D03*
X452842D03*
X456687Y543563D03*
X459837D03*
X459793Y539443D03*
X456643D03*
X463345Y581679D03*
X464767Y74997D03*
X467630Y98747D03*
X464480D03*
X467626Y94743D03*
X464476D03*
X470570Y163503D03*
X467420D03*
X470623Y157235D03*
X467473D03*
X466495Y581679D03*
X469992Y613207D03*
X466842D03*
X491304Y227953D03*
X488154D03*
X484992Y223746D03*
X488142D03*
X492157Y242877D03*
X495307D03*
X487013Y539525D03*
X483863D03*
X485465Y643604D03*
X488615D03*
X486806Y634796D03*
X483656D03*
X485363Y639623D03*
X488513D03*
X490623Y634603D03*
X493773D03*
X485465Y655604D03*
X488615D03*
X485465Y651604D03*
X488615D03*
Y647604D03*
X485465D03*
Y675604D03*
X488615D03*
X485465Y671604D03*
X488615D03*
X485465Y667604D03*
X488615D03*
X485465Y679628D03*
X488615D03*
X493447Y706582D03*
Y714582D03*
Y718582D03*
Y710582D03*
X496123Y230820D03*
X499273D03*
X505430Y436725D03*
X508580D03*
X497745Y449761D03*
X500895D03*
X497818Y445294D03*
X500968D03*
X509230Y441125D03*
X500763Y613598D03*
X503913D03*
X507551Y634818D03*
X504401D03*
Y638780D03*
X507551D03*
X498060Y660178D03*
X501210D03*
X500185Y650626D03*
X497035D03*
X500174Y646569D03*
X497024D03*
X496855Y687669D03*
X500005D03*
X496597Y706582D03*
Y714582D03*
Y718582D03*
Y710582D03*
X515780Y436725D03*
X512630D03*
X512380Y441125D03*
X515280Y609042D03*
X512130D03*
X521613Y615387D03*
X524763D03*
X516939Y634449D03*
X513789D03*
X541660Y211632D03*
X540132Y234993D03*
Y238993D03*
Y246993D03*
Y242993D03*
X535631Y624227D03*
X538781D03*
X535631Y620227D03*
X538781D03*
X544810Y211632D03*
X543282Y234993D03*
Y238993D03*
Y246993D03*
Y242993D03*
X548347Y274262D03*
X545197D03*
X550545Y292524D03*
X547395D03*
X550245Y296824D03*
X547095D03*
X550245Y301124D03*
X547095D03*
X553840Y439007D03*
X550690D03*
X550671Y443048D03*
X553821D03*
X550965Y460656D03*
X554115D03*
X550865Y456156D03*
X554015D03*
X548784Y617102D03*
X545634D03*
X572363Y103123D03*
X564984Y210682D03*
X561834D03*
X564984Y214682D03*
X561834D03*
X563615Y460956D03*
X560465D03*
X563515Y456156D03*
X560365D03*
X564213Y528325D03*
X561063D03*
X564213Y532225D03*
X561063D03*
Y524325D03*
X564213D03*
X568963Y545425D03*
X572113D03*
Y540825D03*
X568963D03*
Y552025D03*
X572113D03*
X569063Y559825D03*
X572213D03*
X568963Y555925D03*
X572113D03*
X568963Y567725D03*
X572113D03*
X568963Y571725D03*
X572113D03*
X568263Y575625D03*
X571413D03*
X568263Y579525D03*
X571413D03*
X568463Y591325D03*
X571613D03*
X568363Y583525D03*
X571513D03*
X568363Y587425D03*
X571513D03*
X575513Y103123D03*
X587043Y117732D03*
X587315Y121836D03*
X587043Y132232D03*
Y128232D03*
X586661Y171906D03*
X589811D03*
X586586Y179955D03*
X589736D03*
X586661Y175906D03*
X589811D03*
X585013Y540625D03*
X581863D03*
Y545225D03*
X585013D03*
X584413Y559445D03*
X581263D03*
X584483Y555235D03*
X581333D03*
X578873Y567253D03*
X582023D03*
X584736Y657848D03*
X581586D03*
X588768Y653385D03*
X584552Y686026D03*
X581402D03*
X584535Y690080D03*
X581385D03*
X584535Y694080D03*
X581385D03*
X603043Y104732D03*
X590193Y117732D03*
X590465Y121836D03*
X590193Y132232D03*
Y128232D03*
X598999Y236295D03*
X602149D03*
X599132Y271893D03*
X602282D03*
Y276393D03*
X599132D03*
X602976Y532108D03*
X599826D03*
Y544108D03*
X602976D03*
X599826Y540108D03*
X602976D03*
X599826Y536108D03*
X602976D03*
X599490Y578903D03*
X602640D03*
X599490Y574903D03*
X602640D03*
X599490Y582903D03*
X602640D03*
Y586903D03*
X599490D03*
X602607Y591105D03*
X599457D03*
X596512Y611545D03*
X593362D03*
X596512Y615545D03*
X593362D03*
X591918Y653385D03*
X610543Y104732D03*
X613693D03*
X618623Y104704D03*
X606193Y104732D03*
X610066Y261804D03*
X613216D03*
X610066Y257804D03*
X613216D03*
X618845Y402052D03*
Y398052D03*
X616829Y546764D03*
X619979D03*
X610044Y655572D03*
X606894D03*
Y650572D03*
X610044D03*
Y660572D03*
X606894D03*
X618059Y675183D03*
X614909D03*
X621773Y104704D03*
X633074Y132241D03*
X636224D03*
X634193Y289089D03*
X637343D03*
X626977Y292591D03*
X630127D03*
X634212Y285042D03*
X637362D03*
X630128Y296525D03*
X626978D03*
X626977Y288469D03*
X630127D03*
X631528Y387178D03*
X628378D03*
X633005Y383132D03*
X629855D03*
X621995Y402052D03*
Y398052D03*
X629708Y418774D03*
X626558D03*
X635286Y516730D03*
X632362Y568745D03*
X635512D03*
X645608Y288706D03*
X648758D03*
X646013Y354885D03*
X642863D03*
X642963Y349785D03*
X646113D03*
X642114Y465888D03*
X638964D03*
Y461888D03*
X642114D03*
X638964Y457888D03*
X642114D03*
X638436Y516730D03*
X643012Y568745D03*
X639862D03*
X651226Y660492D03*
Y655072D03*
Y650072D03*
Y645072D03*
Y716674D03*
X648076D03*
X651226Y720674D03*
X648076D03*
X651226Y724674D03*
X648076D03*
X651226Y728674D03*
X648076D03*
X666336Y149428D03*
Y145428D03*
X666649Y164091D03*
Y160091D03*
X666313Y228335D03*
Y224335D03*
X666899Y242845D03*
Y238845D03*
X658272Y311365D03*
X655122D03*
X660861Y369552D03*
X664011D03*
X667861D03*
X654855Y470065D03*
X658005D03*
X657905Y487265D03*
X654755D03*
X657936Y482930D03*
X654786D03*
X657936Y478630D03*
X654786D03*
X658005Y491665D03*
X654855D03*
X661848Y617431D03*
X664998D03*
X654376Y660492D03*
Y655072D03*
Y650072D03*
Y645072D03*
X669486Y149428D03*
Y145428D03*
X669799Y164091D03*
Y160091D03*
X672020Y185259D03*
X675170D03*
X669463Y228335D03*
Y224335D03*
X670049Y242845D03*
Y238845D03*
X671011Y369552D03*
X678264Y369598D03*
X675114D03*
X672248Y532470D03*
X675398D03*
X678159Y519375D03*
X675009D03*
X672248Y540752D03*
X675398D03*
Y536752D03*
X672248D03*
Y544752D03*
X675398D03*
X672248Y548752D03*
X675398D03*
X693962Y145071D03*
X697112D03*
X693962Y149571D03*
X697112D03*
X698050Y216868D03*
X694900D03*
X698050Y221368D03*
X694900D03*
X707736Y513230D03*
X704586D03*
X712820Y513434D03*
X715970D03*
X701023Y549815D03*
X704173D03*
X703151Y535399D03*
X706301D03*
X731507Y460479D03*
X731670Y467368D03*
X731227Y500100D03*
X731425Y496000D03*
X731227Y504054D03*
X716586Y535030D03*
X719736D03*
X728875Y682700D03*
X725725D03*
X728975Y690800D03*
X725825D03*
X728875Y686700D03*
X725725D03*
X728975Y698800D03*
X725825D03*
X728975Y694800D03*
X725825D03*
X728975Y702800D03*
X725825D03*
X724325Y707800D03*
X727475D03*
X724325Y719800D03*
X727475D03*
X724325Y715800D03*
X727475D03*
X724325Y711800D03*
X727475D03*
X724325Y727800D03*
X727475D03*
X724325Y723800D03*
X727475D03*
X734657Y460479D03*
X734820Y467368D03*
X736954Y483641D03*
X740104D03*
X736976Y478975D03*
X740126D03*
X736925Y475000D03*
X740075D03*
X736835Y487639D03*
X739985D03*
X745075Y496800D03*
X741925D03*
X734377Y500100D03*
X741925Y501000D03*
X745075D03*
X734575Y496000D03*
X739425Y492500D03*
X742575D03*
X734377Y504054D03*
X737675Y641829D03*
X740825D03*
X737675Y653829D03*
X740825D03*
X737675Y649829D03*
X740825D03*
X737675Y645829D03*
X740825D03*
X754998Y446532D03*
X751848D03*
X754998Y455532D03*
X751848D03*
X754998Y451032D03*
X751848D03*
X755075Y475000D03*
X751925D03*
Y479000D03*
X755075D03*
X752075Y492500D03*
X748925D03*
Y488500D03*
X752075D03*
X761984Y559513D03*
X758834D03*
G54D80*
X177593Y438791D03*
X179562D03*
Y427177D03*
X177593D03*
X181530Y438791D03*
X183499D03*
Y427177D03*
X181530D03*
X273021Y31186D03*
Y19572D03*
X274990Y31186D03*
X276958D03*
X278927D03*
Y19572D03*
X276958D03*
X274990D03*
X313280Y603407D03*
X311311D03*
X309343D03*
X307374D03*
Y615021D03*
X309343D03*
X311311D03*
X313280D03*
X399967Y603543D03*
Y615157D03*
X405873Y603543D03*
X403904D03*
X401936D03*
Y615157D03*
X403904D03*
X405873D03*
G54D119*
X417659Y485373D03*
Y490373D03*
Y495373D03*
Y500373D03*
X441359Y485373D03*
Y500373D03*
Y495373D03*
Y490373D03*
G54D62*
X143617Y453259D03*
Y450700D03*
Y448141D03*
Y445582D03*
X258863Y632992D03*
Y635551D03*
Y638110D03*
Y640669D03*
G54D173*
X723275Y155655D03*
Y234461D03*
G54D44*
X86880Y143269D03*
X749968Y29361D03*
G54D155*
X605796Y174845D03*
G54D146*
X557207Y235893D03*
Y270863D03*
X572955Y235893D03*
X571380D03*
X569805D03*
X568231D03*
X566656D03*
X565081D03*
X563506D03*
X561931D03*
X560357D03*
X558782D03*
Y270863D03*
X560357D03*
X561931D03*
X563506D03*
X565081D03*
X566656D03*
X568231D03*
X569805D03*
X571380D03*
X572955D03*
X585553Y235893D03*
X583979D03*
X582404D03*
X580829D03*
X579254D03*
X577679D03*
X576105D03*
X574530D03*
Y270863D03*
X576105D03*
X577679D03*
X579254D03*
X580829D03*
X582404D03*
X583979D03*
X585553D03*
G54D137*
X509464Y452420D03*
Y453995D03*
Y455569D03*
Y457144D03*
Y458719D03*
Y460294D03*
Y461869D03*
Y463443D03*
Y465018D03*
Y466593D03*
Y468168D03*
Y469743D03*
Y471317D03*
Y472892D03*
X537416Y453995D03*
Y452420D03*
Y469743D03*
Y468168D03*
Y466593D03*
Y465018D03*
Y463443D03*
Y461869D03*
Y460294D03*
Y458719D03*
Y457144D03*
Y455569D03*
Y472892D03*
Y471317D03*
G54D128*
X436202Y492873D03*
G54D26*
X47292Y422630D03*
Y441446D03*
X72488Y422630D03*
Y441446D03*
X439566Y418705D03*
Y438705D03*
X464762Y418705D03*
Y438705D03*
G54D53*
X115150Y605559D03*
X110520Y627269D03*
X113270Y635559D03*
X111120Y657269D03*
X133410Y607269D03*
X143110Y612533D03*
X137230Y623734D03*
X150360Y622884D03*
X668320Y585031D03*
X666470Y593397D03*
X657270Y603848D03*
X667930Y599681D03*
X675130Y591687D03*
G54D174*
X727607Y564179D03*
Y582179D03*
Y573179D03*
G54D54*
X136024Y145866D03*
X430906D03*
G54D27*
X45220Y471985D03*
X45546Y488556D03*
X45330Y480233D03*
X56820Y471985D03*
X57146Y488556D03*
X56930Y480233D03*
X143823Y687539D03*
X155423D03*
X195809Y450491D03*
X184209D03*
X291237Y42886D03*
X279637D03*
X291237Y51290D03*
X279637D03*
X295064Y591707D03*
X306664D03*
X387657Y591843D03*
X399257D03*
G54D45*
X85951Y383568D03*
Y404368D03*
X100951Y383568D03*
X95951D03*
X90951D03*
Y404368D03*
X95951D03*
X100951D03*
X224269Y602633D03*
Y623433D03*
X239269Y602633D03*
X234269D03*
X229269D03*
Y623433D03*
X234269D03*
X239269D03*
X352079Y381319D03*
X347079D03*
Y409953D03*
X352079D03*
X362079Y381319D03*
X357079D03*
Y409953D03*
X362079D03*
G54D90*
X193473Y688002D03*
X189733D03*
X185993D03*
Y678356D03*
X193473D03*
X207473Y688002D03*
X203733D03*
X199993D03*
Y678356D03*
X207473D03*
X226993Y688002D03*
Y678356D03*
X220845Y688002D03*
X217105D03*
X213365D03*
Y678356D03*
X220845D03*
X234473Y688002D03*
X230733D03*
X234473Y678356D03*
X240493Y688002D03*
Y678356D03*
X247973Y688002D03*
X244233D03*
X247973Y678356D03*
X257733Y688002D03*
X253993D03*
Y678356D03*
X261473Y688002D03*
Y678356D03*
G54D165*
X683806Y158536D03*
Y168182D03*
X683844Y237342D03*
Y246988D03*
X691286Y158536D03*
X687546D03*
Y168182D03*
X691286D03*
X691324Y237342D03*
X687584D03*
Y246988D03*
X691324D03*
G54D36*
X64089Y489779D03*
Y492338D03*
Y494898D03*
Y497457D03*
X80553D03*
G54D18*
X22935Y602945D03*
Y599795D03*
X18603Y611764D03*
Y614914D03*
X27018Y13036D03*
Y16186D03*
X37599Y44149D03*
X33677Y34564D03*
Y37714D03*
X37599Y47299D03*
X34140Y547324D03*
Y544174D03*
X30140Y547324D03*
Y544174D03*
X26145Y547371D03*
Y544221D03*
X32270Y608415D03*
Y605265D03*
X28270Y608415D03*
Y605265D03*
X41599Y44149D03*
X45578D03*
X49559D03*
X41599Y47299D03*
X45578D03*
X49559D03*
X46981Y65593D03*
Y62443D03*
X50981Y65593D03*
Y62443D03*
X54703Y115946D03*
Y119096D03*
X46811Y115664D03*
Y118814D03*
X50906Y510709D03*
Y513859D03*
X51337Y526060D03*
Y522910D03*
X46140Y547324D03*
Y544174D03*
X50140D03*
Y547324D03*
X44270Y608415D03*
Y605265D03*
X48270D03*
Y608415D03*
X66981Y65593D03*
Y62443D03*
X62981D03*
Y65593D03*
X54981D03*
Y62443D03*
X67831Y145032D03*
Y141882D03*
X61022Y180712D03*
Y183862D03*
X65169Y183921D03*
Y180771D03*
X60729Y204326D03*
Y207476D03*
X64906Y207595D03*
Y204445D03*
X60032Y228683D03*
Y231833D03*
X60182Y249949D03*
X60177Y246022D03*
Y242872D03*
X60029Y235880D03*
Y239030D03*
X60182Y253099D03*
X55351Y522907D03*
Y526057D03*
X59299Y529203D03*
Y526053D03*
X79360Y43076D03*
Y39926D03*
X70745Y170036D03*
X71730Y180744D03*
Y177594D03*
X70745Y173186D03*
X71778Y212026D03*
Y215176D03*
X71758Y218914D03*
Y222064D03*
X80369Y250679D03*
X80391Y243309D03*
Y246459D03*
X80369Y253829D03*
X72368Y290582D03*
Y293732D03*
X82368D03*
Y290582D03*
X75573Y503994D03*
Y507144D03*
X80368Y509170D03*
Y506020D03*
X99968Y371107D03*
Y374257D03*
X95968Y371107D03*
Y374257D03*
X91458Y509198D03*
Y506048D03*
X102257Y172049D03*
Y175199D03*
X113620Y398184D03*
Y401334D03*
X109342Y413499D03*
Y410349D03*
X112072Y483758D03*
Y486908D03*
X108026Y486861D03*
Y483711D03*
X114372Y512558D03*
Y515708D03*
X109972Y512558D03*
Y515708D03*
X126072Y483758D03*
Y486908D03*
X129607Y689212D03*
Y692362D03*
X146380Y27366D03*
Y24216D03*
X137009Y32160D03*
Y35310D03*
X145210Y54510D03*
Y57660D03*
X149157Y57580D03*
Y54430D03*
X141160Y57630D03*
Y54480D03*
X137704Y408853D03*
Y412003D03*
X137759Y689175D03*
Y681175D03*
Y684325D03*
X133607Y689212D03*
X137759Y692325D03*
X133607Y692362D03*
X158181Y14450D03*
Y17600D03*
X154592Y24216D03*
Y27366D03*
X150592D03*
Y24216D03*
X163933Y37475D03*
Y34325D03*
X151101Y445079D03*
Y441929D03*
X151145Y463434D03*
Y466584D03*
X162663Y575608D03*
Y572458D03*
X158430Y575710D03*
Y572560D03*
X157963Y636958D03*
Y640108D03*
X164812Y666374D03*
Y669524D03*
X175335Y14913D03*
Y18063D03*
X171254Y14872D03*
Y18022D03*
X179361Y401571D03*
Y404721D03*
X167861Y424146D03*
X171993Y420771D03*
Y417621D03*
X175993D03*
Y420771D03*
X167861Y427296D03*
X166646Y484538D03*
Y487688D03*
X179263Y575708D03*
Y572558D03*
X170930Y575710D03*
Y572560D03*
X166663Y575608D03*
Y572458D03*
X175263Y575708D03*
Y572558D03*
X172455Y732775D03*
Y735925D03*
X183419Y397314D03*
Y394164D03*
X183361Y401571D03*
Y404721D03*
X191803Y433565D03*
Y436715D03*
X196410Y643700D03*
X191910D03*
X187410D03*
X196410Y653700D03*
Y656850D03*
X187410Y653700D03*
Y656850D03*
X196410Y646850D03*
X191910D03*
X187410D03*
X189940Y715931D03*
Y719081D03*
X185440Y715931D03*
Y719081D03*
X194440Y715898D03*
Y719048D03*
Y739081D03*
Y727581D03*
Y730731D03*
X189940Y727581D03*
Y730731D03*
X185440Y727581D03*
Y730731D03*
X189940Y739081D03*
X185440D03*
X194440Y742231D03*
X189940D03*
X185440D03*
X211660Y391753D03*
Y388603D03*
X208729Y379173D03*
Y382323D03*
X211700Y398689D03*
Y395539D03*
X202009Y465628D03*
Y462478D03*
X205410Y643700D03*
X200910D03*
X205410Y653700D03*
Y656850D03*
X200910Y653700D03*
Y656850D03*
X205410Y646850D03*
X200910D03*
X198940Y715931D03*
Y719081D03*
X207940Y715931D03*
Y719081D03*
X203440Y715898D03*
Y719048D03*
X207940Y739081D03*
X203440D03*
X198940D03*
X207940Y727581D03*
Y730731D03*
X203440Y727581D03*
Y730731D03*
X198940Y727581D03*
Y730731D03*
X207940Y742231D03*
X203440D03*
X198940D03*
X212729Y379173D03*
Y382323D03*
X216729Y379173D03*
Y382323D03*
X220729Y379173D03*
Y382323D03*
X224729Y379173D03*
Y382323D03*
X221228Y396690D03*
Y393540D03*
X225228Y396690D03*
Y393540D03*
X223953Y469967D03*
Y466817D03*
X219640Y479308D03*
Y476158D03*
X221129Y639089D03*
Y635939D03*
X225179Y639089D03*
Y635939D03*
X221440Y739081D03*
X225940Y727581D03*
Y730731D03*
X212440Y739081D03*
X216940D03*
X212440Y730731D03*
Y727581D03*
X225940Y739081D03*
X221440Y730731D03*
Y727581D03*
X216940Y730731D03*
Y727581D03*
X221440Y742231D03*
X212440D03*
X216940D03*
X225940D03*
X232729Y382323D03*
Y379173D03*
X228729Y382323D03*
Y379173D03*
X236729Y382323D03*
Y379173D03*
X240729Y382323D03*
Y379173D03*
X228242Y469924D03*
Y466774D03*
X242009Y466578D03*
Y469728D03*
X237609Y466578D03*
Y469728D03*
X233309Y466578D03*
Y469728D03*
X241909Y478128D03*
Y474978D03*
X237609Y478128D03*
Y474978D03*
X233309Y478128D03*
Y474978D03*
X229199Y635939D03*
Y639089D03*
X229584Y649349D03*
Y646199D03*
X237451D03*
Y649349D03*
X241670Y649253D03*
Y646103D03*
X233584Y649349D03*
Y646199D03*
X234940Y727581D03*
Y730731D03*
X239440Y739081D03*
X230440D03*
X239440Y730731D03*
Y727581D03*
X234940Y739081D03*
X230440Y730731D03*
Y727581D03*
X239440Y742231D03*
X230440D03*
X234940D03*
X253511Y60208D03*
Y57058D03*
X244729Y379173D03*
Y382323D03*
X248729Y379173D03*
Y382323D03*
X252729D03*
Y379173D03*
X256729D03*
Y382323D03*
X254798Y420929D03*
Y424079D03*
X258798Y420929D03*
Y424079D03*
X251309Y466078D03*
Y469228D03*
X255509Y465978D03*
Y469128D03*
X246109Y478128D03*
Y474978D03*
X255509Y478128D03*
Y474978D03*
X251309Y478128D03*
Y474978D03*
X257109Y582978D03*
Y586128D03*
X246313Y632759D03*
Y629609D03*
X246293Y645233D03*
Y648383D03*
X257440Y739081D03*
X252940Y727581D03*
Y730731D03*
X243940Y727581D03*
Y730731D03*
X248440Y739081D03*
Y730731D03*
Y727581D03*
X252940Y739081D03*
X257440Y730731D03*
Y727581D03*
X243940Y739081D03*
X257440Y742231D03*
X248440D03*
X252940D03*
X243940D03*
X267421Y13166D03*
Y10016D03*
X271421D03*
Y13166D03*
X263289Y19691D03*
Y16541D03*
X267987Y68029D03*
Y71179D03*
X271987Y68029D03*
Y71179D03*
X260729Y379173D03*
Y382323D03*
X272729Y379173D03*
Y382323D03*
X264729D03*
Y379173D03*
X268729Y382323D03*
Y379173D03*
X262798Y420929D03*
Y424079D03*
X266732Y420093D03*
Y416943D03*
X260609Y465978D03*
Y469128D03*
Y478128D03*
Y474978D03*
X269109Y478128D03*
Y474978D03*
X273809Y582978D03*
Y586128D03*
X269609Y582978D03*
Y586128D03*
X261940Y739081D03*
X266440D03*
X270940D03*
X266440Y730731D03*
Y727581D03*
X270940Y730731D03*
Y727581D03*
X261940Y730731D03*
Y727581D03*
Y742231D03*
X266440D03*
X270940D03*
X287233Y25708D03*
Y28858D03*
X275987Y68029D03*
Y71179D03*
X283987Y68029D03*
Y71179D03*
X279987Y68029D03*
Y71179D03*
X287987Y68029D03*
Y71179D03*
X289142Y372173D03*
Y369023D03*
X288729Y382323D03*
Y379173D03*
X280729D03*
Y382323D03*
X276729Y379173D03*
Y382323D03*
X284729D03*
Y379173D03*
X286710Y398785D03*
Y395635D03*
X276347Y448426D03*
Y451576D03*
X278109Y582978D03*
Y586128D03*
X282309Y582978D03*
Y586128D03*
X275440Y739081D03*
X279940Y727581D03*
Y730731D03*
X284440Y739081D03*
X288940Y727581D03*
Y730731D03*
X275440D03*
Y727581D03*
X279940Y739081D03*
X288940D03*
X284440Y730731D03*
Y727581D03*
X275440Y742231D03*
X284440D03*
X279940D03*
X288940D03*
X305142Y372173D03*
Y369023D03*
X297142Y372173D03*
Y369023D03*
X293142Y372173D03*
Y369023D03*
X301142Y372173D03*
Y369023D03*
X292729Y382323D03*
Y379173D03*
X298972Y608639D03*
Y605489D03*
X302440Y739081D03*
X297940Y727581D03*
Y730731D03*
X293440Y739081D03*
X297940D03*
X293440Y730731D03*
Y727581D03*
X302440Y742231D03*
X293440D03*
X297940D03*
X316466Y68029D03*
Y71179D03*
X312466Y68029D03*
Y71179D03*
X308466Y68029D03*
Y71179D03*
X320466Y68029D03*
Y71179D03*
X320374Y292653D03*
Y295803D03*
X314640Y319227D03*
Y316077D03*
X318640Y319227D03*
Y316077D03*
X310640Y319227D03*
Y316077D03*
X321110Y334011D03*
Y330861D03*
X309142Y369023D03*
Y372173D03*
X312824Y387863D03*
Y391013D03*
X313222Y378983D03*
Y382133D03*
X316938Y407069D03*
Y410219D03*
X319135Y594112D03*
Y597262D03*
X318880Y621427D03*
Y624577D03*
X314910D03*
Y621427D03*
X314848Y636418D03*
Y639568D03*
X307574Y636613D03*
Y639763D03*
X314940Y719731D03*
Y716581D03*
X311440Y739081D03*
X320440D03*
X315940D03*
X306940Y727581D03*
Y730731D03*
X311440D03*
Y727581D03*
X320440Y730731D03*
Y727581D03*
X315940Y730731D03*
Y727581D03*
X306940Y739081D03*
X311440Y742231D03*
X320440D03*
X315940D03*
X306940D03*
X324466Y68029D03*
Y71179D03*
X324441Y295764D03*
Y292614D03*
X332348Y307752D03*
Y310902D03*
X322640Y319227D03*
Y316077D03*
X326640Y319227D03*
Y316077D03*
X330640Y319227D03*
Y316077D03*
X325700Y327721D03*
Y337951D03*
Y334801D03*
Y330871D03*
X331302Y429920D03*
Y426770D03*
X337012Y509444D03*
Y506294D03*
X332512Y509444D03*
Y506294D03*
X327739Y509656D03*
Y506506D03*
X336688Y537828D03*
Y540978D03*
X332088Y541078D03*
Y537928D03*
X336267Y572677D03*
Y569527D03*
X323036Y614013D03*
Y617163D03*
X323583Y636439D03*
Y639589D03*
X322940Y719731D03*
Y716581D03*
X324940Y739081D03*
X333940D03*
X329440D03*
X324940Y730731D03*
Y727581D03*
X333940Y730731D03*
Y727581D03*
X329440Y730731D03*
Y727581D03*
X324940Y742231D03*
X333940D03*
X329440D03*
X349490Y60647D03*
Y63797D03*
X341512Y509444D03*
Y506294D03*
X346012Y509444D03*
Y506294D03*
X350512Y509444D03*
Y506294D03*
X340388Y569570D03*
Y572720D03*
X347606Y713349D03*
Y710199D03*
X346940Y739081D03*
X342940Y727581D03*
Y730731D03*
X338440Y739081D03*
X351940Y727581D03*
Y730731D03*
X342940Y739081D03*
X347440Y730731D03*
Y727581D03*
X338440Y730731D03*
Y727581D03*
X350940Y739081D03*
X346940Y742231D03*
X338440D03*
X342940D03*
X350940D03*
X358940Y60647D03*
Y63797D03*
X365026Y329623D03*
Y326473D03*
X358210Y446344D03*
Y449494D03*
X368943Y509323D03*
Y512473D03*
X368238Y516378D03*
Y519528D03*
X365433Y540086D03*
Y543236D03*
X361433Y540086D03*
Y543236D03*
X367477Y627663D03*
Y630813D03*
X379051Y60991D03*
X370053Y60823D03*
X379051Y64141D03*
X370053Y63973D03*
X374207Y473374D03*
Y476524D03*
X374203Y484874D03*
Y488024D03*
X380786Y514797D03*
Y517947D03*
X386999Y61186D03*
X395080Y61360D03*
X386999Y64336D03*
X395080Y64510D03*
X395656Y516297D03*
X399837D03*
X387221Y531263D03*
Y534413D03*
X395656Y519447D03*
X399837D03*
X391559Y609125D03*
Y605975D03*
X386464Y640267D03*
Y637117D03*
X390482D03*
Y640267D03*
X411608Y514020D03*
Y510870D03*
X411834Y548430D03*
Y545280D03*
X407834D03*
Y548430D03*
X415605Y615038D03*
Y618188D03*
X411473Y621563D03*
Y624713D03*
X407473D03*
Y621563D03*
X423845Y550973D03*
Y554123D03*
X428039Y550949D03*
Y554099D03*
X428060Y559112D03*
Y562262D03*
X423829Y559032D03*
Y562182D03*
X432152Y559098D03*
Y562248D03*
X432351Y550933D03*
Y554083D03*
X417781Y689290D03*
Y686140D03*
X418440Y739081D03*
X430940D03*
X426440D03*
X421940Y727581D03*
Y730731D03*
X422440Y739081D03*
X430940Y730731D03*
Y727581D03*
X426440Y730731D03*
Y727581D03*
X418440Y742231D03*
X430940D03*
X426440D03*
X422440D03*
X446304Y71848D03*
Y74998D03*
X439749Y509637D03*
Y512787D03*
X443768Y518161D03*
X439762Y518106D03*
X447758Y518161D03*
X443845Y509635D03*
Y512785D03*
X445729Y534196D03*
Y531046D03*
X441651Y534276D03*
Y531126D03*
X443768Y521311D03*
X439762Y521256D03*
X447758Y521311D03*
X443028Y543127D03*
Y546277D03*
X446536Y553518D03*
Y550368D03*
X436219Y559133D03*
Y562283D03*
X442207Y629045D03*
Y632195D03*
X443940Y739081D03*
X448440Y727581D03*
Y730731D03*
X439940Y739081D03*
X435440D03*
X448440D03*
X435440Y730731D03*
Y727581D03*
X439940Y730731D03*
Y727581D03*
X443940Y742231D03*
X439940D03*
X435440D03*
X448440D03*
X450682Y71690D03*
Y74840D03*
X452115Y191819D03*
Y188669D03*
X450937Y486264D03*
Y489414D03*
X460722Y532351D03*
X456722D03*
X450367Y546436D03*
Y543286D03*
X460722Y535501D03*
X456722D03*
X450790Y553519D03*
Y550369D03*
X461588Y550463D03*
Y553613D03*
X451940Y689081D03*
X461440D03*
X456440D03*
X451940Y692231D03*
X461440D03*
X456440D03*
X452940Y739081D03*
X457440Y727581D03*
Y730731D03*
X461940Y739081D03*
X457440D03*
X452940Y742231D03*
X461940D03*
X457440D03*
X470623Y154085D03*
Y157235D03*
X471221Y194784D03*
Y197934D03*
X465291Y537985D03*
Y534835D03*
X478411Y597114D03*
Y593964D03*
X474397D03*
Y597114D03*
X474884Y607476D03*
Y604326D03*
X473436Y626379D03*
Y629529D03*
X469444Y629940D03*
Y633090D03*
X465940Y689081D03*
X470440D03*
X474940D03*
X465940Y692231D03*
X470440D03*
X474940D03*
X470940Y739081D03*
X474940D03*
X466440Y727581D03*
Y730731D03*
X470430Y730748D03*
Y727598D03*
X474930Y730748D03*
Y727598D03*
X479430Y730748D03*
Y727598D03*
X466440Y739081D03*
X478940D03*
X470940Y742231D03*
X474940D03*
X466440D03*
X478940D03*
X488438Y103048D03*
Y106198D03*
X483538Y103048D03*
Y106198D03*
X492955Y106179D03*
Y103029D03*
X495276Y198703D03*
Y195553D03*
X491171Y195574D03*
Y198724D03*
X484280Y195416D03*
Y198566D03*
X485719Y276271D03*
Y279421D03*
X494238Y603450D03*
Y606600D03*
X487240Y739081D03*
X491540D03*
X482940D03*
X492440Y730731D03*
Y727581D03*
X487940Y730731D03*
Y727581D03*
X483440Y730731D03*
Y727581D03*
X487240Y742231D03*
X491540D03*
X482940D03*
X508955Y106179D03*
Y103029D03*
X496955Y106179D03*
Y103029D03*
X504955Y106179D03*
Y103029D03*
X500955Y106179D03*
Y103029D03*
X508300Y201875D03*
Y198725D03*
X504052Y202146D03*
Y205296D03*
X507638Y522050D03*
Y525200D03*
X502038Y525900D03*
Y522750D03*
X502238Y603450D03*
Y606600D03*
X498238Y603450D03*
Y606600D03*
X500140Y739081D03*
X504140D03*
X495840D03*
X504940Y727581D03*
Y730731D03*
X509670Y730633D03*
Y727483D03*
X508140Y739081D03*
X496940Y730731D03*
Y727581D03*
X500140Y742231D03*
X504140D03*
X495840D03*
X508140D03*
X520955Y106179D03*
Y103029D03*
X516955Y106179D03*
Y103029D03*
X512955Y106179D03*
Y103029D03*
X524955Y106179D03*
Y103029D03*
X516657Y200990D03*
X520500Y200925D03*
X524500D03*
X512200Y198625D03*
Y201775D03*
X512160Y211450D03*
Y214600D03*
X516657Y204140D03*
X520500Y204075D03*
X524500D03*
X521800Y214675D03*
Y211525D03*
X513500Y221468D03*
Y224618D03*
X519675Y238308D03*
Y241458D03*
X515675Y238308D03*
Y241458D03*
X524675D03*
Y238308D03*
X526440Y425081D03*
Y428231D03*
X519840Y430981D03*
Y434131D03*
X526440Y437731D03*
Y434581D03*
X525474Y512154D03*
Y515304D03*
X526638Y611200D03*
Y608050D03*
X518940Y726981D03*
Y730131D03*
X520940Y739081D03*
X523940Y727581D03*
Y730731D03*
X512140Y739081D03*
X514940Y727581D03*
Y730731D03*
X516940Y739081D03*
X525440D03*
X520940Y742231D03*
X512140D03*
X516940D03*
X525440D03*
X536955Y103029D03*
Y106179D03*
X532955D03*
Y103029D03*
X528955Y106179D03*
Y103029D03*
X532500Y200925D03*
X540500D03*
X528500D03*
X536657Y200990D03*
X532500Y204075D03*
X531929Y216238D03*
Y219388D03*
X535929Y216238D03*
Y219388D03*
X540500Y204075D03*
X528500D03*
X536657Y204140D03*
X530940Y425081D03*
Y428231D03*
X540940Y425081D03*
Y428231D03*
X535940Y425081D03*
Y428231D03*
X541440Y437731D03*
Y434581D03*
X536440Y437731D03*
Y434581D03*
X531440Y437731D03*
Y434581D03*
X529474Y512154D03*
Y515304D03*
X542438Y607850D03*
Y611000D03*
X534638Y607950D03*
Y611100D03*
X530738D03*
Y607950D03*
X536068Y629326D03*
Y632476D03*
X541440Y716168D03*
Y713018D03*
X531570Y716345D03*
Y713195D03*
X541940Y739081D03*
X532940Y727581D03*
Y730731D03*
X529940Y739081D03*
X534440D03*
X541940Y730731D03*
Y727581D03*
X528440Y730731D03*
Y727581D03*
X541940Y742231D03*
X529940D03*
X534440D03*
X547248Y103161D03*
Y100011D03*
X555938Y100048D03*
Y103198D03*
X551454D03*
Y100048D03*
X553909Y201089D03*
X549909D03*
X557909D03*
X544500Y200925D03*
X553909Y204239D03*
X549909D03*
X557909D03*
X544500Y204075D03*
X545940Y425081D03*
Y428231D03*
X549940Y425081D03*
Y428231D03*
X555140Y448752D03*
Y451902D03*
X551140D03*
Y448752D03*
X546938Y607850D03*
Y611000D03*
X543400Y632456D03*
Y629306D03*
X549940Y716168D03*
Y713018D03*
X546440Y739081D03*
X550940D03*
X555440D03*
X546440Y730731D03*
Y727581D03*
X550940Y730731D03*
Y727581D03*
X555440Y730731D03*
Y727581D03*
X546440Y742231D03*
X550940D03*
X555440D03*
X565938Y100048D03*
Y103198D03*
X561909Y201089D03*
Y204239D03*
X564354Y286277D03*
Y283127D03*
X559140Y448752D03*
Y451902D03*
X562812Y627509D03*
Y630659D03*
X565074Y716168D03*
Y713018D03*
X564440Y727581D03*
Y730731D03*
X568940Y739081D03*
X573440Y727581D03*
Y730731D03*
X559940Y739081D03*
X573440D03*
X568940Y730731D03*
Y727581D03*
X564440Y739081D03*
X559940Y730731D03*
Y727581D03*
X568940Y742231D03*
X559940D03*
X573440D03*
X564440D03*
X586842Y155799D03*
X586769Y166461D03*
Y163311D03*
X586842Y158949D03*
X587707Y226968D03*
Y223818D03*
X579707Y226968D03*
Y223818D03*
X583707Y226968D03*
Y223818D03*
X589107Y289518D03*
Y292668D03*
X588437Y564120D03*
Y560970D03*
X586369Y590017D03*
Y593167D03*
X578399Y589937D03*
Y593087D03*
X582399Y589937D03*
Y593087D03*
X582620Y625963D03*
Y622813D03*
X589800Y683909D03*
Y687059D03*
X583440Y739081D03*
X587940Y727581D03*
Y730731D03*
Y739081D03*
X583440Y730731D03*
Y727581D03*
Y742231D03*
X587940D03*
X590842Y155799D03*
X590769Y166461D03*
Y163311D03*
X590842Y158949D03*
X590598Y202307D03*
Y205457D03*
X591707Y226968D03*
Y223818D03*
X595707Y226968D03*
Y223818D03*
X593107Y289518D03*
Y292668D03*
X604338Y344760D03*
Y341610D03*
X604091Y352754D03*
Y349604D03*
X604493Y361140D03*
Y357990D03*
X596437Y564120D03*
Y560970D03*
X600437Y564120D03*
Y560970D03*
X604437Y564120D03*
Y560970D03*
X592437Y564120D03*
Y560970D03*
X596940Y727581D03*
Y730731D03*
X601440Y739081D03*
X605940D03*
X592440D03*
Y730731D03*
Y727581D03*
X601440Y730731D03*
Y727581D03*
X605940Y730731D03*
Y727581D03*
X596940Y739081D03*
X601440Y742231D03*
X605940D03*
X592440D03*
X596940D03*
X611988Y407850D03*
X615928D03*
X611988Y411000D03*
X615928D03*
X614338Y418820D03*
Y415670D03*
X618368Y418830D03*
Y415680D03*
X612937Y564320D03*
Y561170D03*
X617437Y564320D03*
Y561170D03*
X608437Y564120D03*
Y560970D03*
X611249Y633125D03*
Y636275D03*
X619302Y633065D03*
Y636215D03*
X607292Y681400D03*
Y678250D03*
X617242Y682697D03*
Y679547D03*
X606972Y688804D03*
Y691954D03*
X613882Y691668D03*
Y694818D03*
X614172Y705076D03*
Y701926D03*
X610172Y705076D03*
Y701926D03*
X610440Y739081D03*
X614940D03*
X619440D03*
X614940Y730731D03*
Y727581D03*
X619440Y730731D03*
Y727581D03*
X610440Y730731D03*
Y727581D03*
Y742231D03*
X614940D03*
X619440D03*
X627369Y300555D03*
Y303705D03*
X621937Y564320D03*
Y561170D03*
X630137Y633742D03*
Y636892D03*
X634137Y633742D03*
Y636892D03*
X628440Y739081D03*
X633130Y738905D03*
X637130D03*
X623940Y739081D03*
X628440Y730731D03*
Y727581D03*
X623940Y730731D03*
Y727581D03*
X628440Y742231D03*
X633130Y742055D03*
X637130D03*
X623940Y742231D03*
X643957Y47525D03*
Y50675D03*
X639957Y47525D03*
Y50675D03*
X645236Y371027D03*
Y367877D03*
X641236Y371027D03*
Y367877D03*
X649236Y371027D03*
Y367877D03*
X651437Y575720D03*
Y572570D03*
X642737Y633842D03*
Y636992D03*
X646737Y633842D03*
Y636992D03*
X650970Y633740D03*
Y636890D03*
X638470Y633740D03*
Y636890D03*
X643500Y738925D03*
Y742075D03*
X655947Y47606D03*
Y50756D03*
X659947Y47606D03*
Y50756D03*
X653352Y285183D03*
Y288333D03*
X653938Y367910D03*
Y371060D03*
X668573Y517014D03*
X664024Y516991D03*
X659933Y517197D03*
X668573Y520164D03*
X664024Y520141D03*
X659933Y520347D03*
X655170Y633840D03*
Y636990D03*
X664870Y673830D03*
Y669424D03*
Y666274D03*
Y676980D03*
X659678Y684907D03*
Y688057D03*
X660660Y742510D03*
Y739360D03*
X654660Y742510D03*
Y739360D03*
X669987Y47536D03*
Y50686D03*
X675927Y47536D03*
Y50686D03*
X679927Y47536D03*
Y50686D03*
X672306Y527718D03*
Y524568D03*
X691161Y512755D03*
Y515905D03*
X686661Y512755D03*
Y515905D03*
X693966Y523712D03*
Y520562D03*
X707176Y43845D03*
X711676D03*
X707176Y46995D03*
X711676D03*
X709400Y743375D03*
Y740225D03*
X713400Y743375D03*
Y740225D03*
X731566Y452628D03*
Y455778D03*
Y445468D03*
Y448618D03*
X726829Y515757D03*
Y512607D03*
X722383Y515757D03*
Y512607D03*
X729400Y743375D03*
Y740225D03*
X721400Y743375D03*
Y740225D03*
X717400Y743375D03*
Y740225D03*
X725400Y743375D03*
Y740225D03*
G36*
G01X157808Y696743D02*
X155446D01*
X154461D01*
X152099D01*
X151115D01*
X148753D01*
Y698833D01*
X144422D01*
Y696723D01*
Y694361D01*
X140879D01*
Y696723D01*
X143640D01*
Y699361D01*
X140879D01*
Y701723D01*
X143640D01*
Y704361D01*
X140879D01*
Y706723D01*
X143640D01*
Y709361D01*
X140879D01*
Y711723D01*
X144422D01*
Y709361D01*
Y707742D01*
X148753D01*
Y709341D01*
X151115D01*
Y709340D01*
X151116Y709341D01*
X152099D01*
X154461D01*
X155446D01*
X157808D01*
Y705798D01*
X157734D01*
X157334D01*
X155446D01*
Y708342D01*
X154461D01*
Y705798D01*
X154434D01*
X154034D01*
X152099D01*
Y708342D01*
X151115D01*
Y705798D01*
X151034D01*
X151029D01*
X150634D01*
X148753D01*
Y706933D01*
X144422D01*
Y706723D01*
Y704361D01*
Y703542D01*
X148753D01*
Y704814D01*
X150634D01*
X151033D01*
X151034D01*
X151115D01*
Y702242D01*
X152099D01*
Y704814D01*
X154034D01*
X154434D01*
X154461D01*
Y702242D01*
X155446D01*
Y704814D01*
X157334D01*
X157696D01*
X157734D01*
X157808D01*
Y701270D01*
X157734D01*
X157334D01*
X155446D01*
X154461D01*
X154434D01*
X154034D01*
X152099D01*
X151115D01*
X151034D01*
X150634D01*
X148753D01*
Y702733D01*
X144422D01*
Y701723D01*
Y699642D01*
X148753D01*
Y700286D01*
X150634D01*
X151032D01*
X151034Y700288D01*
Y700286D01*
X151115D01*
Y697642D01*
X152099D01*
Y700286D01*
X154034D01*
X154434D01*
X154461D01*
Y697642D01*
X155446D01*
Y700286D01*
X157334D01*
X157734D01*
X157808D01*
Y696743D01*
G37*
G54D81*
X174739Y430031D03*
Y432000D03*
Y433968D03*
Y435937D03*
X186353D03*
Y433968D03*
Y432000D03*
Y430031D03*
X270167Y22426D03*
Y24395D03*
Y26363D03*
Y28332D03*
X281781D03*
Y26363D03*
Y24395D03*
Y22426D03*
X304520Y606261D03*
Y608230D03*
Y610198D03*
Y612167D03*
X316134D03*
Y610198D03*
Y608230D03*
Y606261D03*
X397113Y606397D03*
Y608366D03*
Y610334D03*
Y612303D03*
X408727D03*
Y610334D03*
Y608366D03*
Y606397D03*
G54D72*
X174380Y46284D03*
G54D129*
X454263Y87816D03*
G54D147*
X553895Y239205D03*
Y240780D03*
Y242354D03*
Y243929D03*
Y245504D03*
Y247079D03*
Y248654D03*
Y250228D03*
Y251803D03*
Y253378D03*
Y254953D03*
Y256528D03*
Y258102D03*
Y259677D03*
Y261252D03*
Y262827D03*
Y264402D03*
Y265976D03*
Y267551D03*
X588865Y250228D03*
Y248654D03*
Y247079D03*
Y245504D03*
Y243929D03*
Y242354D03*
Y240780D03*
Y239205D03*
Y265976D03*
Y264402D03*
Y262827D03*
Y261252D03*
Y259677D03*
Y258102D03*
Y256528D03*
Y254953D03*
Y253378D03*
Y251803D03*
Y267551D03*
G54D156*
X605796Y189845D03*
Y204845D03*
X611702Y185690D03*
Y178997D03*
Y200690D03*
Y193997D03*
G54D138*
X510779Y534746D03*
X509205D03*
X507630D03*
X506055D03*
X504480D03*
X502905D03*
X501331D03*
Y595770D03*
X502905D03*
X504480D03*
X506055D03*
X507630D03*
X509205D03*
X510779D03*
X526527Y534746D03*
X524953D03*
X523378D03*
X521803D03*
X520228D03*
X518653D03*
X517079D03*
X515504D03*
X513929D03*
X512354D03*
Y595770D03*
X513929D03*
X515504D03*
X517079D03*
X518653D03*
X520228D03*
X521803D03*
X523378D03*
X524953D03*
X526527D03*
X542275Y534746D03*
X540701D03*
X539126D03*
X537551D03*
X535976D03*
X534401D03*
X532827D03*
X531252D03*
X529677D03*
X528102D03*
Y595770D03*
X529677D03*
X531252D03*
X532827D03*
X534401D03*
X535976D03*
X537551D03*
X539126D03*
X540701D03*
X542275D03*
X550149Y534746D03*
X548575D03*
X547000D03*
X545425D03*
X543850D03*
Y595770D03*
X545425D03*
X547000D03*
X548575D03*
X550149D03*
G54D73*
X173100Y40352D03*
G54D148*
X557454Y624762D03*
X548793D03*
Y631652D03*
X557454D03*
G54D64*
X163583Y82480D03*
X161221D03*
X158859D03*
X162402Y114763D03*
X160040D03*
X180119Y82480D03*
X177757D03*
X175394D03*
X173032D03*
X170670D03*
X168308D03*
X165946D03*
X178938Y114763D03*
X176576D03*
X174213D03*
X171851D03*
X169489D03*
X167127D03*
X164765D03*
X194292Y82480D03*
X191930D03*
X189568D03*
X187205D03*
X184843D03*
X182481D03*
X195473Y114763D03*
X193111D03*
X190749D03*
X188387D03*
X186024D03*
X183662D03*
X181300D03*
X210827Y82480D03*
X208465D03*
X206103D03*
X203741D03*
X201379D03*
X199016D03*
X196654D03*
X209646Y114763D03*
X207284D03*
X204922D03*
X202560D03*
X200198D03*
X197835D03*
X227363Y82480D03*
X225001D03*
X222639D03*
X220276D03*
X217914D03*
X215552D03*
X213190D03*
X226182Y114763D03*
X223820D03*
X221457D03*
X219095D03*
X216733D03*
X214371D03*
X212009D03*
X241536Y82480D03*
X239174D03*
X236812D03*
X234450D03*
X232087D03*
X229725D03*
X242717Y114763D03*
X240355D03*
X237993D03*
X235631D03*
X233268D03*
X230906D03*
X228544D03*
X258072Y82480D03*
X255709D03*
X253347D03*
X259253Y114763D03*
X256891D03*
X254528D03*
X274607Y82480D03*
X272245D03*
X269883D03*
X267520D03*
X265158D03*
X262796D03*
X260434D03*
X273426Y114763D03*
X271064D03*
X268702D03*
X266339D03*
X263977D03*
X261615D03*
X288780Y82480D03*
X286418D03*
X284056D03*
X281694D03*
X279331D03*
X276969D03*
X289961Y114763D03*
X287599D03*
X285237D03*
X282875D03*
X280513D03*
X278150D03*
X275788D03*
X305316Y82480D03*
X302953D03*
X300591D03*
X298229D03*
X295867D03*
X293505D03*
X291142D03*
X306497Y114763D03*
X304135D03*
X301772D03*
X299410D03*
X297048D03*
X294686D03*
X292324D03*
X321851Y82480D03*
X319489D03*
X317127D03*
X314765D03*
X312402D03*
X310040D03*
X307678D03*
X320670Y114763D03*
X318308D03*
X315946D03*
X313583D03*
X311221D03*
X308859D03*
X336024Y82480D03*
X333662D03*
X331300D03*
X328938D03*
X326576D03*
X324213D03*
X337205Y114763D03*
X334843D03*
X332481D03*
X330119D03*
X327757D03*
X325394D03*
X323032D03*
X352560Y82480D03*
X350198D03*
X347835D03*
X345473D03*
X343111D03*
X340749D03*
X338387D03*
X353741Y114763D03*
X351379D03*
X349016D03*
X346654D03*
X344292D03*
X341930D03*
X339568D03*
X369095Y82480D03*
X366733D03*
X364371D03*
X362009D03*
X359646D03*
X357284D03*
X354922D03*
X367914Y114763D03*
X365552D03*
X363190D03*
X360827D03*
X358465D03*
X356103D03*
X383268Y82480D03*
X380906D03*
X378544D03*
X376182D03*
X373820D03*
X371457D03*
X384450Y114763D03*
X382087D03*
X379725D03*
X377363D03*
X375001D03*
X372639D03*
X370276D03*
X399804Y82480D03*
X397442D03*
X395079D03*
X392717D03*
X390355D03*
X387993D03*
X385631D03*
X400985Y114763D03*
X398623D03*
X396261D03*
X393898D03*
X391536D03*
X389174D03*
X386812D03*
X406891Y82480D03*
X404528D03*
X402166D03*
X408072Y114763D03*
X405709D03*
X403347D03*
G54D157*
X609300Y534523D03*
X618946D03*
X609300Y542003D03*
Y538263D03*
X618946Y542003D03*
X682880Y547065D03*
Y539585D03*
X692526D03*
Y543325D03*
Y547065D03*
G54D28*
X51395Y500840D03*
X65440Y164548D03*
X59640D03*
X66055Y223944D03*
X60255D03*
X57195Y500840D03*
X85829Y535202D03*
X79182Y583713D03*
X73382D03*
X91629Y535202D03*
X91717Y587077D03*
X97517D03*
X103080Y535202D03*
X108880D03*
X130102Y738065D03*
X124302D03*
X145375Y305640D03*
X139575D03*
X165512Y50968D03*
X159712D03*
X208209Y476153D03*
X214009D03*
X220428Y583822D03*
X226228D03*
X238952Y583627D03*
X233152D03*
X238852Y589327D03*
X233052D03*
X256606Y387964D03*
X250806D03*
X265696Y446936D03*
X271496D03*
X275509Y668795D03*
X269709D03*
X324696Y363647D03*
X330496D03*
X324696Y369147D03*
X330496D03*
X324732Y374642D03*
X330532D03*
X332439Y380334D03*
X326639D03*
X342520Y303938D03*
X348320D03*
X340926Y317597D03*
X346726D03*
X409149Y71906D03*
X414949D03*
X448182Y262291D03*
X447975Y604522D03*
X457394Y187205D03*
X463194D03*
X453982Y262291D03*
X453775Y604522D03*
X473153Y617880D03*
X467353D03*
X495888Y655413D03*
X501688D03*
X535772Y253862D03*
X541572D03*
X714559Y563230D03*
X720359D03*
X725495Y593262D03*
X731295D03*
X757507Y564565D03*
X763307D03*
X757614Y570468D03*
X763414D03*
G54D19*
X36900Y12883D03*
X34341D03*
X31782D03*
Y20757D03*
X34341D03*
X36900D03*
G54D82*
X173892Y482546D03*
X181470Y485105D03*
Y482546D03*
X173892Y487664D03*
X181470D03*
X506279Y209758D03*
Y214876D03*
X498701Y209758D03*
Y212317D03*
Y214876D03*
X506356Y219563D03*
Y224681D03*
X498778Y219563D03*
Y222122D03*
Y224681D03*
G54D37*
X63237Y512883D03*
G54D166*
X677206Y469943D03*
X681143D03*
X677206Y466006D03*
X681143D03*
X677206Y462069D03*
X681143D03*
X677206Y458132D03*
X681143D03*
X677206Y485692D03*
X681143D03*
X677206Y481755D03*
X681143D03*
X677206Y477817D03*
X681143D03*
X677206Y473881D03*
X681143D03*
X677206Y493566D03*
X681143D03*
X677206Y489629D03*
X681143D03*
X685080Y469943D03*
X689017D03*
X692955D03*
X696891D03*
X685080Y466006D03*
X689017D03*
X692955D03*
X696891D03*
X685080Y462069D03*
X689017D03*
X692955D03*
X696891D03*
X685080Y458132D03*
X689017D03*
X692955D03*
X696891D03*
X685080Y485692D03*
X689017D03*
X692955D03*
X696891D03*
X685080Y481755D03*
X689017D03*
X692955D03*
X696891D03*
X685080Y477817D03*
X689017D03*
X692955D03*
X696891D03*
X685080Y473881D03*
X689017D03*
X692955D03*
X696891D03*
X685080Y493566D03*
X689017D03*
X692955D03*
X696891D03*
X685080Y489629D03*
X689017D03*
X692955D03*
X696891D03*
X700829Y469943D03*
X704766D03*
X708703D03*
X712640D03*
X700829Y466006D03*
X704766D03*
X708703D03*
X712640D03*
X700829Y462069D03*
X704766D03*
X708703D03*
X712640D03*
X700829Y458132D03*
X704766D03*
X708703D03*
X712640D03*
X700829Y485692D03*
X704766D03*
X708703D03*
X712640D03*
X700829Y481755D03*
X704766D03*
X708703D03*
X712640D03*
X700829Y477817D03*
X704766D03*
X708703D03*
X712640D03*
X700829Y473881D03*
X704766D03*
X708703D03*
X712640D03*
X700829Y493566D03*
X704766D03*
X708703D03*
X712640D03*
X700829Y489629D03*
X704766D03*
X708703D03*
X712640D03*
G54D139*
X514780Y28803D03*
X524780D03*
X514780Y38803D03*
X524780D03*
X534780Y28803D03*
X544780D03*
X534780Y38803D03*
X544780D03*
X554780Y28803D03*
X577371D03*
X587371D03*
X577371Y38803D03*
X587371D03*
X597371Y28803D03*
X607371D03*
X597371Y38803D03*
X607371D03*
X617371Y28803D03*
X639963D03*
Y38803D03*
X649963Y28803D03*
Y38803D03*
X659963Y28803D03*
X669963D03*
X659963Y38803D03*
X669963D03*
X679963Y28803D03*
G54D46*
X77499Y457491D03*
Y480521D03*
G54D175*
X749907Y573179D03*
G54D55*
X125142Y406358D03*
X642452Y304580D03*
G54D91*
X204724Y279523D03*
X207874D03*
X211024D03*
X204724Y282673D03*
Y285823D03*
Y288973D03*
Y292123D03*
Y295273D03*
X207874Y282673D03*
Y285823D03*
Y288973D03*
Y292123D03*
Y295273D03*
X211024Y282673D03*
Y285823D03*
Y288973D03*
Y292123D03*
Y295273D03*
X204724Y301573D03*
Y298423D03*
Y311023D03*
Y307873D03*
Y304723D03*
X207874Y301573D03*
Y298423D03*
Y311023D03*
Y307873D03*
Y304723D03*
X211024Y301573D03*
Y298423D03*
Y311023D03*
Y307873D03*
Y304723D03*
X204724Y314173D03*
X207874Y317323D03*
Y314173D03*
X211024Y317323D03*
Y314173D03*
X204724Y317323D03*
X223624Y279523D03*
X220474D03*
X214174D03*
X217324D03*
X226774D03*
X223624Y282673D03*
X220474D03*
X217324D03*
X214174D03*
X223624Y285823D03*
Y288973D03*
Y292123D03*
Y295273D03*
X220474Y285823D03*
Y288973D03*
Y292123D03*
Y295273D03*
X217324Y285823D03*
Y288973D03*
Y292123D03*
Y295273D03*
X214174Y285823D03*
Y288973D03*
Y292123D03*
Y295273D03*
X226774Y282673D03*
Y295273D03*
Y292123D03*
Y288973D03*
Y285823D03*
X223624Y301573D03*
Y298423D03*
X220474Y301573D03*
Y298423D03*
X217324Y301573D03*
Y298423D03*
X214174Y301573D03*
Y298423D03*
X223624Y311023D03*
Y307873D03*
Y304723D03*
X220474Y311023D03*
Y307873D03*
Y304723D03*
X217324Y311023D03*
Y307873D03*
Y304723D03*
X214174Y311023D03*
Y307873D03*
Y304723D03*
X226774Y298423D03*
Y301573D03*
Y304723D03*
Y307873D03*
Y311023D03*
X223624Y317323D03*
Y314173D03*
X220474Y317323D03*
Y314173D03*
X217324Y317323D03*
Y314173D03*
X214174Y317323D03*
Y314173D03*
X226774D03*
Y317323D03*
X229924Y279523D03*
X236224D03*
X233074D03*
X242524D03*
X239374D03*
X229924Y282673D03*
X236224D03*
X233074D03*
X242524D03*
X239374D03*
X229924Y295273D03*
Y292123D03*
Y288973D03*
Y285823D03*
X236224D03*
Y288973D03*
Y292123D03*
Y295273D03*
X233074Y285823D03*
Y288973D03*
Y292123D03*
Y295273D03*
X242524Y285823D03*
Y288973D03*
Y292123D03*
Y295273D03*
X239374Y285823D03*
Y288973D03*
Y292123D03*
Y295273D03*
X229924Y298423D03*
Y301573D03*
X236224D03*
Y298423D03*
X233074Y301573D03*
Y298423D03*
X242524Y301573D03*
Y298423D03*
X239374Y301573D03*
Y298423D03*
X229924Y304723D03*
Y307873D03*
Y311023D03*
X236224D03*
Y307873D03*
Y304723D03*
X233074Y311023D03*
Y307873D03*
Y304723D03*
X242524Y311023D03*
Y307873D03*
Y304723D03*
X239374Y311023D03*
Y307873D03*
Y304723D03*
X229924Y314173D03*
Y317323D03*
X236224D03*
Y314173D03*
X233074Y317323D03*
Y314173D03*
X242524Y317323D03*
Y314173D03*
X239374Y317323D03*
Y314173D03*
X245674Y279523D03*
X248824D03*
X251974D03*
X245674Y282673D03*
Y285823D03*
Y288973D03*
Y292123D03*
Y295273D03*
X248824Y282673D03*
X251974D03*
X248824Y285823D03*
Y288973D03*
Y292123D03*
Y295273D03*
X251974D03*
Y292123D03*
Y288973D03*
Y285823D03*
X245674Y301573D03*
Y298423D03*
Y311023D03*
Y307873D03*
Y304723D03*
X248824Y301573D03*
Y298423D03*
X251974D03*
Y301573D03*
X248824Y311023D03*
Y307873D03*
Y304723D03*
X251974D03*
Y307873D03*
Y311023D03*
X245674Y317323D03*
Y314173D03*
X248824Y317323D03*
Y314173D03*
X251974D03*
Y317323D03*
G54D176*
G01X38493Y-241864D02*
Y-246864D01*
G01X37036Y-241864D02*
X39950D01*
G01X44860Y-246864D02*
X42326D01*
Y-241864D01*
X44860D01*
G01X43846Y-244281D02*
X42326D01*
G01X47426Y-241864D02*
Y-246864D01*
X49960D01*
G01X53793Y-247031D02*
X53666Y-246947D01*
Y-246781D01*
X53793Y-246697D01*
X53920Y-246781D01*
Y-246947D01*
X53793Y-247031D01*
G01Y-244781D02*
X53666Y-244697D01*
Y-244531D01*
X53793Y-244447D01*
X53920Y-244531D01*
Y-244697D01*
X53793Y-244781D01*
G01X58576Y-248531D02*
X57943Y-247697D01*
X57626Y-246864D01*
Y-243531D01*
X57943Y-242697D01*
X58576Y-241864D01*
G01X63993D02*
X63486Y-242031D01*
X63106Y-242447D01*
X62853Y-242947D01*
X62663Y-243614D01*
X62600Y-244364D01*
X62663Y-245114D01*
X62853Y-245781D01*
X63106Y-246281D01*
X63486Y-246697D01*
X63993Y-246864D01*
X64500Y-246697D01*
X64880Y-246281D01*
X65133Y-245781D01*
X65323Y-245114D01*
X65386Y-244364D01*
X65323Y-243614D01*
X65133Y-242947D01*
X64880Y-242447D01*
X64500Y-242031D01*
X63993Y-241864D01*
G01X67700Y-245864D02*
X68080Y-246447D01*
X68586Y-246781D01*
X69156Y-246864D01*
X69663Y-246781D01*
X70170Y-246364D01*
X70486Y-245864D01*
X70550Y-245364D01*
X70423Y-244781D01*
X69980Y-244364D01*
X69536Y-244197D01*
X68966D01*
G01X69536D02*
X69916Y-243947D01*
X70233Y-243531D01*
X70360Y-243031D01*
X70233Y-242531D01*
X69916Y-242114D01*
X69346Y-241864D01*
X68776Y-241947D01*
X68206Y-242281D01*
G01X74510Y-248531D02*
X75143Y-247697D01*
X75460Y-246864D01*
Y-243531D01*
X75143Y-242697D01*
X74510Y-241864D01*
G01X77900Y-245864D02*
X78280Y-246447D01*
X78786Y-246781D01*
X79356Y-246864D01*
X79863Y-246781D01*
X80370Y-246364D01*
X80686Y-245864D01*
X80750Y-245364D01*
X80623Y-244781D01*
X80180Y-244364D01*
X79736Y-244197D01*
X79166D01*
G01X79736D02*
X80116Y-243947D01*
X80433Y-243531D01*
X80560Y-243031D01*
X80433Y-242531D01*
X80116Y-242114D01*
X79546Y-241864D01*
X78976Y-241947D01*
X78406Y-242281D01*
G01X83190Y-242697D02*
X83570Y-242197D01*
X84013Y-241947D01*
X84520Y-241864D01*
X85153Y-242031D01*
X85596Y-242447D01*
X85723Y-242947D01*
X85660Y-243447D01*
X85406Y-243864D01*
X84140Y-244697D01*
X83570Y-245281D01*
X83190Y-246114D01*
X83063Y-246864D01*
X85723D01*
G01X89366D02*
X89493Y-245781D01*
X89683Y-244864D01*
X89936Y-244031D01*
X90253Y-243114D01*
X90760Y-241864D01*
X88226D01*
G01X93770Y-245197D02*
X95416D01*
G01X98490Y-242697D02*
X98870Y-242197D01*
X99313Y-241947D01*
X99820Y-241864D01*
X100453Y-242031D01*
X100896Y-242447D01*
X101023Y-242947D01*
X100960Y-243447D01*
X100706Y-243864D01*
X99440Y-244697D01*
X98870Y-245281D01*
X98490Y-246114D01*
X98363Y-246864D01*
X101023D01*
G01X103400Y-245864D02*
X103780Y-246447D01*
X104286Y-246781D01*
X104856Y-246864D01*
X105363Y-246781D01*
X105870Y-246364D01*
X106186Y-245864D01*
X106250Y-245364D01*
X106123Y-244781D01*
X105680Y-244364D01*
X105236Y-244197D01*
X104666D01*
G01X105236D02*
X105616Y-243947D01*
X105933Y-243531D01*
X106060Y-243031D01*
X105933Y-242531D01*
X105616Y-242114D01*
X105046Y-241864D01*
X104476Y-241947D01*
X103906Y-242281D01*
G01X110653Y-246864D02*
Y-241864D01*
X108310Y-245447D01*
X111476D01*
G01X113600Y-246114D02*
X113980Y-246531D01*
X114423Y-246781D01*
X114993Y-246864D01*
X115563Y-246697D01*
X116006Y-246364D01*
X116323Y-245781D01*
X116386Y-245114D01*
X116260Y-244447D01*
X115943Y-244031D01*
X115500Y-243697D01*
X115056Y-243614D01*
X114613Y-243697D01*
X114043Y-244031D01*
X114233Y-241864D01*
X115943D01*
G01X123990Y-246864D02*
Y-241864D01*
X126396D01*
G01X125510Y-244281D02*
X123990D01*
G01X128710Y-246864D02*
X130293Y-241864D01*
X131876Y-246864D01*
G01X131306Y-245114D02*
X129280D01*
G01X134063Y-246864D02*
X136723Y-241864D01*
G01X134063D02*
X136723Y-246864D01*
G01X140493Y-247031D02*
X140366Y-246947D01*
Y-246781D01*
X140493Y-246697D01*
X140620Y-246781D01*
Y-246947D01*
X140493Y-247031D01*
G01Y-244781D02*
X140366Y-244697D01*
Y-244531D01*
X140493Y-244447D01*
X140620Y-244531D01*
Y-244697D01*
X140493Y-244781D01*
G01X145276Y-248531D02*
X144643Y-247697D01*
X144326Y-246864D01*
Y-243531D01*
X144643Y-242697D01*
X145276Y-241864D01*
G01X150693D02*
X150186Y-242031D01*
X149806Y-242447D01*
X149553Y-242947D01*
X149363Y-243614D01*
X149300Y-244364D01*
X149363Y-245114D01*
X149553Y-245781D01*
X149806Y-246281D01*
X150186Y-246697D01*
X150693Y-246864D01*
X151200Y-246697D01*
X151580Y-246281D01*
X151833Y-245781D01*
X152023Y-245114D01*
X152086Y-244364D01*
X152023Y-243614D01*
X151833Y-242947D01*
X151580Y-242447D01*
X151200Y-242031D01*
X150693Y-241864D01*
G01X154400Y-245864D02*
X154780Y-246447D01*
X155286Y-246781D01*
X155856Y-246864D01*
X156363Y-246781D01*
X156870Y-246364D01*
X157186Y-245864D01*
X157250Y-245364D01*
X157123Y-244781D01*
X156680Y-244364D01*
X156236Y-244197D01*
X155666D01*
G01X156236D02*
X156616Y-243947D01*
X156933Y-243531D01*
X157060Y-243031D01*
X156933Y-242531D01*
X156616Y-242114D01*
X156046Y-241864D01*
X155476Y-241947D01*
X154906Y-242281D01*
G01X161210Y-248531D02*
X161843Y-247697D01*
X162160Y-246864D01*
Y-243531D01*
X161843Y-242697D01*
X161210Y-241864D01*
G01X164600Y-245864D02*
X164980Y-246447D01*
X165486Y-246781D01*
X166056Y-246864D01*
X166563Y-246781D01*
X167070Y-246364D01*
X167386Y-245864D01*
X167450Y-245364D01*
X167323Y-244781D01*
X166880Y-244364D01*
X166436Y-244197D01*
X165866D01*
G01X166436D02*
X166816Y-243947D01*
X167133Y-243531D01*
X167260Y-243031D01*
X167133Y-242531D01*
X166816Y-242114D01*
X166246Y-241864D01*
X165676Y-241947D01*
X165106Y-242281D01*
G01X170016Y-246281D02*
X170460Y-246697D01*
X170966Y-246864D01*
X171473Y-246697D01*
X171916Y-246197D01*
X172233Y-245447D01*
X172360Y-244697D01*
Y-243781D01*
X172233Y-243031D01*
X171916Y-242364D01*
X171536Y-242031D01*
X171093Y-241864D01*
X170586Y-242031D01*
X170206Y-242364D01*
X169953Y-242864D01*
X169826Y-243531D01*
X169953Y-244114D01*
X170270Y-244697D01*
X170650Y-245031D01*
X171093Y-245114D01*
X171600Y-244947D01*
X171980Y-244531D01*
X172360Y-243781D01*
G01X176066Y-246864D02*
X176193Y-245781D01*
X176383Y-244864D01*
X176636Y-244031D01*
X176953Y-243114D01*
X177460Y-241864D01*
X174926D01*
G01X180470Y-245197D02*
X182116D01*
G01X185000Y-245864D02*
X185380Y-246447D01*
X185886Y-246781D01*
X186456Y-246864D01*
X186963Y-246781D01*
X187470Y-246364D01*
X187786Y-245864D01*
X187850Y-245364D01*
X187723Y-244781D01*
X187280Y-244364D01*
X186836Y-244197D01*
X186266D01*
G01X186836D02*
X187216Y-243947D01*
X187533Y-243531D01*
X187660Y-243031D01*
X187533Y-242531D01*
X187216Y-242114D01*
X186646Y-241864D01*
X186076Y-241947D01*
X185506Y-242281D01*
G01X190290Y-244781D02*
X190733Y-244197D01*
X191113Y-243864D01*
X191620Y-243697D01*
X192063Y-243864D01*
X192380Y-244197D01*
X192633Y-244697D01*
X192696Y-245281D01*
X192633Y-245781D01*
X192380Y-246281D01*
X192000Y-246697D01*
X191556Y-246864D01*
X191050Y-246697D01*
X190606Y-246197D01*
X190353Y-245447D01*
X190290Y-244614D01*
X190416Y-243531D01*
X190606Y-242947D01*
X190923Y-242364D01*
X191366Y-241947D01*
X191810Y-241864D01*
X192253Y-242031D01*
X192570Y-242447D01*
G01X196593Y-246864D02*
Y-241864D01*
X195833Y-242864D01*
G01Y-246864D02*
X197353D01*
G01X202453D02*
Y-241864D01*
X200110Y-245447D01*
X203276D01*
G01X26493Y-176864D02*
Y-251864D01*
X526493D01*
Y-176864D01*
X26493D01*
G01X221493D02*
Y-251864D01*
G01Y-226864D02*
X324493D01*
Y-201864D01*
G01X221493D02*
X324493D01*
G01X332000Y-236864D02*
Y-231864D01*
X333266D01*
X333773Y-232114D01*
X334153Y-232447D01*
X334470Y-232947D01*
X334723Y-233531D01*
X334786Y-234364D01*
X334723Y-235197D01*
X334470Y-235781D01*
X334153Y-236281D01*
X333773Y-236614D01*
X333266Y-236864D01*
X332000D01*
G01X336910D02*
X338493Y-231864D01*
X340076Y-236864D01*
G01X339506Y-235114D02*
X337480D01*
G01X343593Y-231864D02*
Y-236864D01*
G01X342136Y-231864D02*
X345050D01*
G01X349960Y-236864D02*
X347426D01*
Y-231864D01*
X349960D01*
G01X348946Y-234281D02*
X347426D01*
G01X353793Y-237031D02*
X353666Y-236947D01*
Y-236781D01*
X353793Y-236697D01*
X353920Y-236781D01*
Y-236947D01*
X353793Y-237031D01*
G01Y-234781D02*
X353666Y-234697D01*
Y-234531D01*
X353793Y-234447D01*
X353920Y-234531D01*
Y-234697D01*
X353793Y-234781D01*
G01X326493Y-176864D02*
Y-251864D01*
G01X324493Y-176864D02*
Y-251864D01*
G01X326493Y-226864D02*
X526493D01*
G01X332126Y-211864D02*
Y-206864D01*
X333646D01*
X334153Y-207114D01*
X334533Y-207697D01*
X334660Y-208364D01*
X334533Y-209031D01*
X334216Y-209531D01*
X333646Y-209781D01*
X332126D01*
G01X337353Y-212031D02*
X339633Y-206864D01*
G01X342136Y-211864D02*
Y-206864D01*
X345050Y-211864D01*
Y-206864D01*
G01X348693Y-212031D02*
X348566Y-211947D01*
Y-211781D01*
X348693Y-211697D01*
X348820Y-211781D01*
Y-211947D01*
X348693Y-212031D01*
G01Y-209781D02*
X348566Y-209697D01*
Y-209531D01*
X348693Y-209447D01*
X348820Y-209531D01*
Y-209697D01*
X348693Y-209781D01*
G01X326493Y-201864D02*
X526493D01*
G01X332126Y-186864D02*
Y-181864D01*
X333646D01*
X334153Y-182114D01*
X334533Y-182697D01*
X334660Y-183364D01*
X334533Y-184031D01*
X334216Y-184531D01*
X333646Y-184781D01*
X332126D01*
G01X337226Y-186864D02*
Y-181864D01*
X338810D01*
X339316Y-182114D01*
X339633Y-182447D01*
X339760Y-183114D01*
X339633Y-183781D01*
X339253Y-184197D01*
X338810Y-184447D01*
X337226D01*
G01X338810D02*
X339760Y-186864D01*
G01X343593D02*
X343086Y-186781D01*
X342643Y-186447D01*
X342263Y-185947D01*
X342010Y-185364D01*
X341883Y-184697D01*
Y-184031D01*
X342010Y-183364D01*
X342263Y-182781D01*
X342643Y-182281D01*
X343086Y-181947D01*
X343593Y-181864D01*
X344100Y-181947D01*
X344543Y-182281D01*
X344923Y-182781D01*
X345176Y-183364D01*
X345303Y-184031D01*
Y-184697D01*
X345176Y-185364D01*
X344923Y-185947D01*
X344543Y-186447D01*
X344100Y-186781D01*
X343593Y-186864D01*
G01X347426Y-185864D02*
X347743Y-186364D01*
X348123Y-186697D01*
X348566Y-186864D01*
X349073Y-186697D01*
X349453Y-186364D01*
X349833Y-185864D01*
X349960Y-185197D01*
Y-181864D01*
G01X355060Y-186864D02*
X352526D01*
Y-181864D01*
X355060D01*
G01X354046Y-184281D02*
X352526D01*
G01X360286Y-182281D02*
X359906Y-182031D01*
X359463Y-181864D01*
X358956D01*
X358386Y-182114D01*
X357943Y-182531D01*
X357626Y-183031D01*
X357373Y-183864D01*
X357310Y-184614D01*
X357436Y-185364D01*
X357626Y-185864D01*
X358006Y-186364D01*
X358450Y-186697D01*
X358893Y-186864D01*
X359336D01*
X359780Y-186697D01*
X360160Y-186447D01*
X360476Y-186114D01*
G01X363993Y-181864D02*
Y-186864D01*
G01X362536Y-181864D02*
X365450D01*
G01X369093Y-187031D02*
X368966Y-186947D01*
Y-186781D01*
X369093Y-186697D01*
X369220Y-186781D01*
Y-186947D01*
X369093Y-187031D01*
G01Y-184781D02*
X368966Y-184697D01*
Y-184531D01*
X369093Y-184447D01*
X369220Y-184531D01*
Y-184697D01*
X369093Y-184781D01*
G01X447126Y-236864D02*
Y-231864D01*
X448710D01*
X449216Y-232114D01*
X449533Y-232447D01*
X449660Y-233114D01*
X449533Y-233781D01*
X449153Y-234197D01*
X448710Y-234447D01*
X447126D01*
G01X448710D02*
X449660Y-236864D01*
G01X454760D02*
X452226D01*
Y-231864D01*
X454760D01*
G01X453746Y-234281D02*
X452226D01*
G01X457010Y-231864D02*
X458593Y-236864D01*
X460176Y-231864D01*
G01X463693Y-237031D02*
X463566Y-236947D01*
Y-236781D01*
X463693Y-236697D01*
X463820Y-236781D01*
Y-236947D01*
X463693Y-237031D01*
G01Y-234781D02*
X463566Y-234697D01*
Y-234531D01*
X463693Y-234447D01*
X463820Y-234531D01*
Y-234697D01*
X463693Y-234781D01*
G01X441493Y-226864D02*
Y-251864D01*
G01X490493Y-226864D02*
Y-251864D01*
G01X-1043962Y-705877D02*
Y2342823D01*
X2300638D01*
Y-705877D01*
X-1043962D01*
G01X37198Y-238524D02*
X37825Y-239049D01*
X38530Y-239364D01*
X39156D01*
X39783Y-239049D01*
X40253Y-238524D01*
X40488Y-237789D01*
X40331Y-237054D01*
X39940Y-236424D01*
X39235Y-236004D01*
X38295Y-235794D01*
X37746Y-235374D01*
X37511Y-234639D01*
X37668Y-233904D01*
X38060Y-233379D01*
X38608Y-233064D01*
X39156D01*
X39705Y-233274D01*
X40175Y-233799D01*
G01X43498Y-239364D02*
Y-233064D01*
G01X46788D02*
Y-239364D01*
G01Y-236214D02*
X43498D01*
G01X50503Y-233064D02*
X52383D01*
G01X51443D02*
Y-239364D01*
G01X50503D02*
X52383D01*
G01X59310D02*
X56176D01*
Y-233064D01*
X59310D01*
G01X58056Y-236109D02*
X56176D01*
G01X62241Y-239364D02*
Y-233064D01*
X65845Y-239364D01*
Y-233064D01*
G01X70186Y-240519D02*
X70500Y-239154D01*
G01X76643Y-233064D02*
Y-239364D01*
G01X74841Y-233064D02*
X78445D01*
G01X80985Y-239364D02*
X82943Y-233064D01*
X84901Y-239364D01*
G01X84196Y-237159D02*
X81690D01*
G01X88303Y-233064D02*
X90183D01*
G01X89243D02*
Y-239364D01*
G01X88303D02*
X90183D01*
G01X93193Y-233064D02*
X94290Y-239364D01*
X95543Y-233064D01*
X96796Y-239364D01*
X97893Y-233064D01*
G01X99885Y-239364D02*
X101843Y-233064D01*
X103801Y-239364D01*
G01X103096Y-237159D02*
X100590D01*
G01X106341Y-239364D02*
Y-233064D01*
X109945Y-239364D01*
Y-233064D01*
G01X119176Y-239364D02*
Y-233064D01*
X121135D01*
X121761Y-233379D01*
X122153Y-233799D01*
X122310Y-234639D01*
X122153Y-235479D01*
X121683Y-236004D01*
X121135Y-236319D01*
X119176D01*
G01X121135D02*
X122310Y-239364D01*
G01X127043Y-239574D02*
X126886Y-239469D01*
Y-239259D01*
X127043Y-239154D01*
X127200Y-239259D01*
Y-239469D01*
X127043Y-239574D01*
G01X133343Y-239364D02*
X132716Y-239259D01*
X132168Y-238839D01*
X131698Y-238209D01*
X131385Y-237474D01*
X131228Y-236634D01*
Y-235794D01*
X131385Y-234954D01*
X131698Y-234219D01*
X132168Y-233589D01*
X132716Y-233169D01*
X133343Y-233064D01*
X133970Y-233169D01*
X134518Y-233589D01*
X134988Y-234219D01*
X135301Y-234954D01*
X135458Y-235794D01*
Y-236634D01*
X135301Y-237474D01*
X134988Y-238209D01*
X134518Y-238839D01*
X133970Y-239259D01*
X133343Y-239364D01*
G01X139643Y-239574D02*
X139486Y-239469D01*
Y-239259D01*
X139643Y-239154D01*
X139800Y-239259D01*
Y-239469D01*
X139643Y-239574D01*
G01X147666Y-233589D02*
X147196Y-233274D01*
X146648Y-233064D01*
X146021D01*
X145316Y-233379D01*
X144768Y-233904D01*
X144376Y-234534D01*
X144063Y-235584D01*
X143985Y-236529D01*
X144141Y-237474D01*
X144376Y-238104D01*
X144846Y-238734D01*
X145395Y-239154D01*
X145943Y-239364D01*
X146491D01*
X147040Y-239154D01*
X147510Y-238839D01*
X147901Y-238419D01*
G01X152243Y-239574D02*
X152086Y-239469D01*
Y-239259D01*
X152243Y-239154D01*
X152400Y-239259D01*
Y-239469D01*
X152243Y-239574D01*
G01X37120Y-229364D02*
Y-223064D01*
G01X40096D02*
X37120Y-226949D01*
G01X40566Y-229364D02*
X38451Y-225164D01*
G01X43420Y-223064D02*
Y-227579D01*
X43733Y-228524D01*
X44360Y-229154D01*
X45143Y-229364D01*
X45926Y-229154D01*
X46553Y-228524D01*
X46866Y-227579D01*
Y-223064D01*
G01X53010Y-229364D02*
X49876D01*
Y-223064D01*
X53010D01*
G01X51756Y-226109D02*
X49876D01*
G01X56803Y-223064D02*
X58683D01*
G01X57743D02*
Y-229364D01*
G01X56803D02*
X58683D01*
G01X68698Y-228524D02*
X69325Y-229049D01*
X70030Y-229364D01*
X70656D01*
X71283Y-229049D01*
X71753Y-228524D01*
X71988Y-227789D01*
X71831Y-227054D01*
X71440Y-226424D01*
X70735Y-226004D01*
X69795Y-225794D01*
X69246Y-225374D01*
X69011Y-224639D01*
X69168Y-223904D01*
X69560Y-223379D01*
X70108Y-223064D01*
X70656D01*
X71205Y-223274D01*
X71675Y-223799D01*
G01X74998Y-229364D02*
Y-223064D01*
G01X78288D02*
Y-229364D01*
G01Y-226214D02*
X74998D01*
G01X80985Y-229364D02*
X82943Y-223064D01*
X84901Y-229364D01*
G01X84196Y-227159D02*
X81690D01*
G01X87441Y-229364D02*
Y-223064D01*
X91045Y-229364D01*
Y-223064D01*
G01X100198Y-229364D02*
Y-223064D01*
G01X103488D02*
Y-229364D01*
G01Y-226214D02*
X100198D01*
G01X106498Y-228524D02*
X107125Y-229049D01*
X107830Y-229364D01*
X108456D01*
X109083Y-229049D01*
X109553Y-228524D01*
X109788Y-227789D01*
X109631Y-227054D01*
X109240Y-226424D01*
X108535Y-226004D01*
X107595Y-225794D01*
X107046Y-225374D01*
X106811Y-224639D01*
X106968Y-223904D01*
X107360Y-223379D01*
X107908Y-223064D01*
X108456D01*
X109005Y-223274D01*
X109475Y-223799D01*
G01X113503Y-223064D02*
X115383D01*
G01X114443D02*
Y-229364D01*
G01X113503D02*
X115383D01*
G01X118785D02*
X120743Y-223064D01*
X122701Y-229364D01*
G01X121996Y-227159D02*
X119490D01*
G01X125241Y-229364D02*
Y-223064D01*
X128845Y-229364D01*
Y-223064D01*
G01X133813Y-226214D02*
X135380D01*
Y-228104D01*
X134910Y-228734D01*
X134361Y-229154D01*
X133578Y-229364D01*
X132795Y-229154D01*
X132246Y-228734D01*
X131776Y-228104D01*
X131463Y-227369D01*
X131306Y-226529D01*
Y-225794D01*
X131463Y-225164D01*
X131776Y-224429D01*
X132246Y-223799D01*
X132716Y-223379D01*
X133343Y-223064D01*
X133891D01*
X134518Y-223274D01*
X134988Y-223694D01*
G01X139486Y-230519D02*
X139800Y-229154D01*
G01X145943Y-223064D02*
Y-229364D01*
G01X144141Y-223064D02*
X147745D01*
G01X150285Y-229364D02*
X152243Y-223064D01*
X154201Y-229364D01*
G01X153496Y-227159D02*
X150990D01*
G01X158543Y-229364D02*
X157916Y-229259D01*
X157368Y-228839D01*
X156898Y-228209D01*
X156585Y-227474D01*
X156428Y-226634D01*
Y-225794D01*
X156585Y-224954D01*
X156898Y-224219D01*
X157368Y-223589D01*
X157916Y-223169D01*
X158543Y-223064D01*
X159170Y-223169D01*
X159718Y-223589D01*
X160188Y-224219D01*
X160501Y-224954D01*
X160658Y-225794D01*
Y-226634D01*
X160501Y-227474D01*
X160188Y-228209D01*
X159718Y-228839D01*
X159170Y-229259D01*
X158543Y-229364D01*
G01X171143D02*
Y-226529D01*
X169576Y-223064D01*
G01X172710D02*
X171143Y-226529D01*
G01X175720Y-223064D02*
Y-227579D01*
X176033Y-228524D01*
X176660Y-229154D01*
X177443Y-229364D01*
X178226Y-229154D01*
X178853Y-228524D01*
X179166Y-227579D01*
Y-223064D01*
G01X181785Y-229364D02*
X183743Y-223064D01*
X185701Y-229364D01*
G01X184996Y-227159D02*
X182490D01*
G01X188241Y-229364D02*
Y-223064D01*
X191845Y-229364D01*
Y-223064D01*
G01X37041Y-219364D02*
Y-213064D01*
X40645Y-219364D01*
Y-213064D01*
G01X45143Y-219364D02*
X44516Y-219259D01*
X43968Y-218839D01*
X43498Y-218209D01*
X43185Y-217474D01*
X43028Y-216634D01*
Y-215794D01*
X43185Y-214954D01*
X43498Y-214219D01*
X43968Y-213589D01*
X44516Y-213169D01*
X45143Y-213064D01*
X45770Y-213169D01*
X46318Y-213589D01*
X46788Y-214219D01*
X47101Y-214954D01*
X47258Y-215794D01*
Y-216634D01*
X47101Y-217474D01*
X46788Y-218209D01*
X46318Y-218839D01*
X45770Y-219259D01*
X45143Y-219364D01*
G01X51443Y-219574D02*
X51286Y-219469D01*
Y-219259D01*
X51443Y-219154D01*
X51600Y-219259D01*
Y-219469D01*
X51443Y-219574D01*
G01X57743Y-219364D02*
Y-213064D01*
X56803Y-214324D01*
G01Y-219364D02*
X58683D01*
G01X64043D02*
X64591Y-219259D01*
X65218Y-218944D01*
X65610Y-218419D01*
X65766Y-217684D01*
X65610Y-216949D01*
X65140Y-216319D01*
X64435Y-216004D01*
X63651D01*
X63181Y-215794D01*
X62790Y-215269D01*
X62633Y-214534D01*
X62868Y-213799D01*
X63416Y-213274D01*
X64043Y-213064D01*
X64670Y-213274D01*
X65218Y-213799D01*
X65453Y-214534D01*
X65296Y-215269D01*
X64905Y-215794D01*
X64435Y-216004D01*
X63651D01*
X62946Y-216319D01*
X62476Y-216949D01*
X62320Y-217684D01*
X62476Y-218419D01*
X62868Y-218944D01*
X63495Y-219259D01*
X64043Y-219364D01*
G01X70343D02*
X70891Y-219259D01*
X71518Y-218944D01*
X71910Y-218419D01*
X72066Y-217684D01*
X71910Y-216949D01*
X71440Y-216319D01*
X70735Y-216004D01*
X69951D01*
X69481Y-215794D01*
X69090Y-215269D01*
X68933Y-214534D01*
X69168Y-213799D01*
X69716Y-213274D01*
X70343Y-213064D01*
X70970Y-213274D01*
X71518Y-213799D01*
X71753Y-214534D01*
X71596Y-215269D01*
X71205Y-215794D01*
X70735Y-216004D01*
X69951D01*
X69246Y-216319D01*
X68776Y-216949D01*
X68620Y-217684D01*
X68776Y-218419D01*
X69168Y-218944D01*
X69795Y-219259D01*
X70343Y-219364D01*
G01X76486Y-220519D02*
X76800Y-219154D01*
G01X80593Y-213064D02*
X81690Y-219364D01*
X82943Y-213064D01*
X84196Y-219364D01*
X85293Y-213064D01*
G01X90810Y-219364D02*
X87676D01*
Y-213064D01*
X90810D01*
G01X89556Y-216109D02*
X87676D01*
G01X93741Y-219364D02*
Y-213064D01*
X97345Y-219364D01*
Y-213064D01*
G01X106498Y-219364D02*
Y-213064D01*
G01X109788D02*
Y-219364D01*
G01Y-216214D02*
X106498D01*
G01X112093Y-213064D02*
X113190Y-219364D01*
X114443Y-213064D01*
X115696Y-219364D01*
X116793Y-213064D01*
G01X118785Y-219364D02*
X120743Y-213064D01*
X122701Y-219364D01*
G01X121996Y-217159D02*
X119490D01*
G01X131855Y-214114D02*
X132325Y-213484D01*
X132873Y-213169D01*
X133500Y-213064D01*
X134283Y-213274D01*
X134831Y-213799D01*
X134988Y-214429D01*
X134910Y-215059D01*
X134596Y-215584D01*
X133030Y-216634D01*
X132325Y-217369D01*
X131855Y-218419D01*
X131698Y-219364D01*
X134988D01*
G01X137841D02*
Y-213064D01*
X141445Y-219364D01*
Y-213064D01*
G01X144220Y-219364D02*
Y-213064D01*
X145786D01*
X146413Y-213379D01*
X146883Y-213799D01*
X147275Y-214429D01*
X147588Y-215164D01*
X147666Y-216214D01*
X147588Y-217264D01*
X147275Y-217999D01*
X146883Y-218629D01*
X146413Y-219049D01*
X145786Y-219364D01*
X144220D01*
G01X156976D02*
Y-213064D01*
X158935D01*
X159561Y-213379D01*
X159953Y-213799D01*
X160110Y-214639D01*
X159953Y-215479D01*
X159483Y-216004D01*
X158935Y-216319D01*
X156976D01*
G01X158935D02*
X160110Y-219364D01*
G01X163120D02*
Y-213064D01*
X164686D01*
X165313Y-213379D01*
X165783Y-213799D01*
X166175Y-214429D01*
X166488Y-215164D01*
X166566Y-216214D01*
X166488Y-217264D01*
X166175Y-217999D01*
X165783Y-218629D01*
X165313Y-219049D01*
X164686Y-219364D01*
X163120D01*
G01X171143Y-219574D02*
X170986Y-219469D01*
Y-219259D01*
X171143Y-219154D01*
X171300Y-219259D01*
Y-219469D01*
X171143Y-219574D01*
G01X61143Y-206664D02*
X58623Y-206247D01*
X56418Y-204581D01*
X54528Y-202081D01*
X53268Y-199164D01*
X52638Y-195831D01*
Y-192497D01*
X53268Y-189164D01*
X54528Y-186247D01*
X56418Y-183748D01*
X58623Y-182081D01*
X61143Y-181664D01*
X63663Y-182081D01*
X65868Y-183748D01*
X67758Y-186247D01*
X69018Y-189164D01*
X69648Y-192497D01*
Y-195831D01*
X69018Y-199164D01*
X67758Y-202081D01*
X65868Y-204581D01*
X63663Y-206247D01*
X61143Y-206664D01*
G01X63663Y-199997D02*
X67443Y-206664D01*
G01X80988Y-189998D02*
Y-201664D01*
X82248Y-204581D01*
X84138Y-206247D01*
X86343Y-206664D01*
X88548Y-206247D01*
X90438Y-204581D01*
X91698Y-201664D01*
G01Y-206664D02*
Y-189998D01*
G01X117213Y-206664D02*
Y-189998D01*
G01Y-192914D02*
X115953Y-191248D01*
X114063Y-190414D01*
X111858Y-189998D01*
X109653Y-190831D01*
X107763Y-192497D01*
X106503Y-194998D01*
X105873Y-198331D01*
X106503Y-201664D01*
X107763Y-204165D01*
X109653Y-205831D01*
X111858Y-206664D01*
X114063Y-206247D01*
X115953Y-204998D01*
X117213Y-203331D01*
G01X131388Y-206664D02*
Y-189998D01*
G01Y-194164D02*
X132648Y-192081D01*
X134538Y-190414D01*
X137058Y-189998D01*
X139263Y-190414D01*
X141153Y-192081D01*
X142098Y-194998D01*
Y-206664D01*
G01X161943Y-181664D02*
Y-206664D01*
G01X157533Y-189998D02*
X166353D01*
G01X192813Y-206664D02*
Y-189998D01*
G01Y-192914D02*
X191553Y-191248D01*
X189663Y-190414D01*
X187458Y-189998D01*
X185253Y-190831D01*
X183363Y-192497D01*
X182103Y-194998D01*
X181473Y-198331D01*
X182103Y-201664D01*
X183363Y-204165D01*
X185253Y-205831D01*
X187458Y-206664D01*
X189663Y-206247D01*
X191553Y-204998D01*
X192813Y-203331D01*
G01X232493Y-186364D02*
Y-194364D01*
X236493D01*
G01X244293D02*
Y-189031D01*
G01Y-189964D02*
X243893Y-189431D01*
X243293Y-189164D01*
X242593Y-189031D01*
X241893Y-189297D01*
X241293Y-189831D01*
X240893Y-190631D01*
X240693Y-191697D01*
X240893Y-192764D01*
X241293Y-193564D01*
X241893Y-194097D01*
X242593Y-194364D01*
X243293Y-194231D01*
X243893Y-193831D01*
X244293Y-193298D01*
G01X248393Y-196764D02*
X248993Y-197031D01*
X249793Y-196764D01*
X250293Y-196231D01*
X250693Y-195564D01*
X251293Y-193431D01*
X252593Y-189031D01*
G01X249393D02*
X251293Y-193431D01*
G01X256993Y-190764D02*
X260193D01*
X259893Y-189831D01*
X259393Y-189297D01*
X258693Y-189031D01*
X257993Y-189164D01*
X257393Y-189564D01*
X256993Y-190497D01*
X256793Y-191298D01*
Y-192097D01*
X256993Y-192897D01*
X257493Y-193697D01*
X258093Y-194231D01*
X258793Y-194364D01*
X259493Y-194097D01*
X260193Y-193298D01*
G01X265093Y-194364D02*
Y-189031D01*
G01Y-190097D02*
X265593Y-189564D01*
X266093Y-189164D01*
X266793Y-189031D01*
X267293Y-189164D01*
X267893Y-189564D01*
G01X254793Y-236364D02*
X257193D01*
G01X255993D02*
Y-244364D01*
G01X254793D02*
X257193D01*
G01X262593D02*
Y-239031D01*
G01Y-240097D02*
X263093Y-239564D01*
X263593Y-239164D01*
X264293Y-239031D01*
X264793Y-239164D01*
X265393Y-239564D01*
G01X270493Y-240764D02*
X273693D01*
X273393Y-239831D01*
X272893Y-239297D01*
X272193Y-239031D01*
X271493Y-239164D01*
X270893Y-239564D01*
X270493Y-240497D01*
X270293Y-241298D01*
Y-242097D01*
X270493Y-242897D01*
X270993Y-243697D01*
X271593Y-244231D01*
X272293Y-244364D01*
X272993Y-244097D01*
X273693Y-243298D01*
G01X278293Y-244364D02*
Y-239031D01*
G01Y-240364D02*
X278693Y-239697D01*
X279293Y-239164D01*
X280093Y-239031D01*
X280793Y-239164D01*
X281393Y-239697D01*
X281693Y-240631D01*
Y-244364D01*
G01X286493Y-240764D02*
X289693D01*
X289393Y-239831D01*
X288893Y-239297D01*
X288193Y-239031D01*
X287493Y-239164D01*
X286893Y-239564D01*
X286493Y-240497D01*
X286293Y-241298D01*
Y-242097D01*
X286493Y-242897D01*
X286993Y-243697D01*
X287593Y-244231D01*
X288293Y-244364D01*
X288993Y-244097D01*
X289693Y-243298D01*
G01X243993Y-219364D02*
Y-211364D01*
X246393D01*
X247193Y-211764D01*
X247793Y-212697D01*
X247993Y-213764D01*
X247793Y-214831D01*
X247293Y-215631D01*
X246393Y-216031D01*
X243993D01*
G01X251493Y-219364D02*
X253993Y-211364D01*
X256493Y-219364D01*
G01X255593Y-216564D02*
X252393D01*
G01X259893Y-218298D02*
X260693Y-218964D01*
X261593Y-219364D01*
X262393D01*
X263193Y-218964D01*
X263793Y-218298D01*
X264093Y-217364D01*
X263893Y-216431D01*
X263393Y-215631D01*
X262493Y-215097D01*
X261293Y-214831D01*
X260593Y-214297D01*
X260293Y-213364D01*
X260493Y-212431D01*
X260993Y-211764D01*
X261693Y-211364D01*
X262393D01*
X263093Y-211631D01*
X263693Y-212297D01*
G01X269993Y-211364D02*
Y-219364D01*
G01X267693Y-211364D02*
X272293D01*
G01X276693Y-216697D02*
X279293D01*
G01X285993Y-211364D02*
Y-219364D01*
G01X283693Y-211364D02*
X288293D01*
G01X293993Y-219364D02*
X293193Y-219231D01*
X292493Y-218697D01*
X291893Y-217897D01*
X291493Y-216964D01*
X291293Y-215897D01*
Y-214831D01*
X291493Y-213764D01*
X291893Y-212831D01*
X292493Y-212031D01*
X293193Y-211497D01*
X293993Y-211364D01*
X294793Y-211497D01*
X295493Y-212031D01*
X296093Y-212831D01*
X296493Y-213764D01*
X296693Y-214831D01*
Y-215897D01*
X296493Y-216964D01*
X296093Y-217897D01*
X295493Y-218697D01*
X294793Y-219231D01*
X293993Y-219364D01*
G01X299993D02*
Y-211364D01*
X302393D01*
X303193Y-211764D01*
X303793Y-212697D01*
X303993Y-213764D01*
X303793Y-214831D01*
X303293Y-215631D01*
X302393Y-216031D01*
X299993D01*
G01X359093Y-237697D02*
X359693Y-236897D01*
X360393Y-236497D01*
X361193Y-236364D01*
X362193Y-236631D01*
X362893Y-237297D01*
X363093Y-238097D01*
X362993Y-238898D01*
X362593Y-239564D01*
X360593Y-240897D01*
X359693Y-241831D01*
X359093Y-243164D01*
X358893Y-244364D01*
X363093D01*
G01X368993Y-236364D02*
X368193Y-236631D01*
X367593Y-237297D01*
X367193Y-238097D01*
X366893Y-239164D01*
X366793Y-240364D01*
X366893Y-241564D01*
X367193Y-242631D01*
X367593Y-243431D01*
X368193Y-244097D01*
X368993Y-244364D01*
X369793Y-244097D01*
X370393Y-243431D01*
X370793Y-242631D01*
X371093Y-241564D01*
X371193Y-240364D01*
X371093Y-239164D01*
X370793Y-238097D01*
X370393Y-237297D01*
X369793Y-236631D01*
X368993Y-236364D01*
G01X376993Y-244364D02*
Y-236364D01*
X375793Y-237964D01*
G01Y-244364D02*
X378193D01*
G01X383093Y-237697D02*
X383693Y-236897D01*
X384393Y-236497D01*
X385193Y-236364D01*
X386193Y-236631D01*
X386893Y-237297D01*
X387093Y-238097D01*
X386993Y-238898D01*
X386593Y-239564D01*
X384593Y-240897D01*
X383693Y-241831D01*
X383093Y-243164D01*
X382893Y-244364D01*
X387093D01*
G01X391193Y-244631D02*
X394793Y-236364D01*
G01X400993Y-244364D02*
Y-236364D01*
X399793Y-237964D01*
G01Y-244364D02*
X402193D01*
G01X408993Y-236364D02*
X408193Y-236631D01*
X407593Y-237297D01*
X407193Y-238097D01*
X406893Y-239164D01*
X406793Y-240364D01*
X406893Y-241564D01*
X407193Y-242631D01*
X407593Y-243431D01*
X408193Y-244097D01*
X408993Y-244364D01*
X409793Y-244097D01*
X410393Y-243431D01*
X410793Y-242631D01*
X411093Y-241564D01*
X411193Y-240364D01*
X411093Y-239164D01*
X410793Y-238097D01*
X410393Y-237297D01*
X409793Y-236631D01*
X408993Y-236364D01*
G01X415193Y-244631D02*
X418793Y-236364D01*
G01X422793Y-242764D02*
X423393Y-243697D01*
X424193Y-244231D01*
X425093Y-244364D01*
X425893Y-244231D01*
X426693Y-243564D01*
X427193Y-242764D01*
X427293Y-241964D01*
X427093Y-241031D01*
X426393Y-240364D01*
X425693Y-240097D01*
X424793D01*
G01X425693D02*
X426293Y-239697D01*
X426793Y-239031D01*
X426993Y-238231D01*
X426793Y-237431D01*
X426293Y-236764D01*
X425393Y-236364D01*
X424493Y-236497D01*
X423593Y-237031D01*
G01X432993Y-244364D02*
Y-236364D01*
X431793Y-237964D01*
G01Y-244364D02*
X434193D01*
G01X358793Y-219364D02*
Y-211364D01*
X360793D01*
X361593Y-211764D01*
X362193Y-212297D01*
X362693Y-213097D01*
X363093Y-214031D01*
X363193Y-215364D01*
X363093Y-216697D01*
X362693Y-217631D01*
X362193Y-218431D01*
X361593Y-218964D01*
X360793Y-219364D01*
X358793D01*
G01X366493D02*
X368993Y-211364D01*
X371493Y-219364D01*
G01X370593Y-216564D02*
X367393D01*
G01X376993Y-211364D02*
Y-219364D01*
G01X374693Y-211364D02*
X379293D01*
G01X383093Y-216031D02*
X383793Y-215097D01*
X384393Y-214564D01*
X385193Y-214297D01*
X385893Y-214564D01*
X386393Y-215097D01*
X386793Y-215897D01*
X386893Y-216831D01*
X386793Y-217631D01*
X386393Y-218431D01*
X385793Y-219097D01*
X385093Y-219364D01*
X384293Y-219097D01*
X383593Y-218298D01*
X383193Y-217097D01*
X383093Y-215764D01*
X383293Y-214031D01*
X383593Y-213097D01*
X384093Y-212164D01*
X384793Y-211497D01*
X385493Y-211364D01*
X386193Y-211631D01*
X386693Y-212297D01*
G01X390393Y-219364D02*
Y-211364D01*
X392993Y-218031D01*
X395593Y-211364D01*
Y-219364D01*
G01X400993Y-211364D02*
Y-219364D01*
G01X398693Y-211364D02*
X403293D01*
G01X406893Y-219364D02*
Y-211364D01*
G01X411093D02*
Y-219364D01*
G01Y-215364D02*
X406893D01*
G01X414793Y-217764D02*
X415393Y-218697D01*
X416193Y-219231D01*
X417093Y-219364D01*
X417893Y-219231D01*
X418693Y-218564D01*
X419193Y-217764D01*
X419293Y-216964D01*
X419093Y-216031D01*
X418393Y-215364D01*
X417693Y-215097D01*
X416793D01*
G01X417693D02*
X418293Y-214697D01*
X418793Y-214031D01*
X418993Y-213231D01*
X418793Y-212431D01*
X418293Y-211764D01*
X417393Y-211364D01*
X416493Y-211497D01*
X415593Y-212031D01*
G01X422493Y-219364D02*
X424993Y-211364D01*
X427493Y-219364D01*
G01X426593Y-216564D02*
X423393D01*
G01X430793Y-219364D02*
Y-211364D01*
X432793D01*
X433593Y-211764D01*
X434193Y-212297D01*
X434693Y-213097D01*
X435093Y-214031D01*
X435193Y-215364D01*
X435093Y-216697D01*
X434693Y-217631D01*
X434193Y-218431D01*
X433593Y-218964D01*
X432793Y-219364D01*
X430793D01*
G01X440993Y-211364D02*
X440193Y-211631D01*
X439593Y-212297D01*
X439193Y-213097D01*
X438893Y-214164D01*
X438793Y-215364D01*
X438893Y-216564D01*
X439193Y-217631D01*
X439593Y-218431D01*
X440193Y-219097D01*
X440993Y-219364D01*
X441793Y-219097D01*
X442393Y-218431D01*
X442793Y-217631D01*
X443093Y-216564D01*
X443193Y-215364D01*
X443093Y-214164D01*
X442793Y-213097D01*
X442393Y-212297D01*
X441793Y-211631D01*
X440993Y-211364D01*
G01X380993Y-186364D02*
Y-194364D01*
G01X378693Y-186364D02*
X383293D01*
G01X387093Y-191031D02*
X387793Y-190097D01*
X388393Y-189564D01*
X389193Y-189297D01*
X389893Y-189564D01*
X390393Y-190097D01*
X390793Y-190897D01*
X390893Y-191831D01*
X390793Y-192631D01*
X390393Y-193431D01*
X389793Y-194097D01*
X389093Y-194364D01*
X388293Y-194097D01*
X387593Y-193298D01*
X387193Y-192097D01*
X387093Y-190764D01*
X387293Y-189031D01*
X387593Y-188097D01*
X388093Y-187164D01*
X388793Y-186497D01*
X389493Y-186364D01*
X390193Y-186631D01*
X390693Y-187297D01*
G01X394393Y-194364D02*
Y-186364D01*
X396993Y-193031D01*
X399593Y-186364D01*
Y-194364D01*
G01X401993Y-197031D02*
X407993D01*
G01X415193Y-187031D02*
X414593Y-186631D01*
X413893Y-186364D01*
X413093D01*
X412193Y-186764D01*
X411493Y-187431D01*
X410993Y-188231D01*
X410593Y-189564D01*
X410493Y-190764D01*
X410693Y-191964D01*
X410993Y-192764D01*
X411593Y-193564D01*
X412293Y-194097D01*
X412993Y-194364D01*
X413693D01*
X414393Y-194097D01*
X414993Y-193697D01*
X415493Y-193164D01*
G01X418393Y-194364D02*
Y-186364D01*
X420993Y-193031D01*
X423593Y-186364D01*
Y-194364D01*
G01X425993Y-197031D02*
X431993D01*
G01X434793Y-194364D02*
Y-186364D01*
X436793D01*
X437593Y-186764D01*
X438193Y-187297D01*
X438693Y-188097D01*
X439093Y-189031D01*
X439193Y-190364D01*
X439093Y-191697D01*
X438693Y-192631D01*
X438193Y-193431D01*
X437593Y-193964D01*
X436793Y-194364D01*
X434793D01*
G01X473793Y-244364D02*
Y-236364D01*
X475793D01*
X476593Y-236764D01*
X477193Y-237297D01*
X477693Y-238097D01*
X478093Y-239031D01*
X478193Y-240364D01*
X478093Y-241697D01*
X477693Y-242631D01*
X477193Y-243431D01*
X476593Y-243964D01*
X475793Y-244364D01*
X473793D01*
G01X503493D02*
Y-236364D01*
X502293Y-237964D01*
G01Y-244364D02*
X504693D01*
G01X509593Y-241031D02*
X510293Y-240097D01*
X510893Y-239564D01*
X511693Y-239297D01*
X512393Y-239564D01*
X512893Y-240097D01*
X513293Y-240897D01*
X513393Y-241831D01*
X513293Y-242631D01*
X512893Y-243431D01*
X512293Y-244097D01*
X511593Y-244364D01*
X510793Y-244097D01*
X510093Y-243298D01*
X509693Y-242097D01*
X509593Y-240764D01*
X509793Y-239031D01*
X510093Y-238097D01*
X510593Y-237164D01*
X511293Y-236497D01*
X511993Y-236364D01*
X512693Y-236631D01*
X513193Y-237297D01*
G54D149*
X571380Y253378D03*
G54D74*
X173100Y33371D03*
G54D47*
X80553Y492338D03*
G54D92*
X209378Y469399D03*
Y462707D03*
X218040Y469399D03*
Y462707D03*
X513167Y422944D03*
X504505D03*
Y429636D03*
X513167D03*
G54D83*
X175463Y609933D03*
X633937Y602745D03*
G54D29*
X55256Y625732D03*
Y637332D03*
X116383Y576727D03*
Y588327D03*
X164948Y8617D03*
Y20217D03*
X181582Y11345D03*
Y22945D03*
X190011Y11535D03*
Y23135D03*
X199840Y11316D03*
Y22916D03*
X456988Y479623D03*
X465255Y479621D03*
X456988Y491223D03*
X465255Y491221D03*
X462344Y499662D03*
Y511262D03*
X718335Y581651D03*
Y593251D03*
X747439Y641672D03*
Y653272D03*
G54D167*
X683386Y626150D03*
X678386D03*
X673386D03*
Y661386D03*
X678386D03*
X683386D03*
X698386Y626150D03*
X693386D03*
X688386D03*
Y661386D03*
X693386D03*
X698386D03*
X713386Y626150D03*
X708386D03*
X703386D03*
Y661386D03*
X708386D03*
X713386D03*
X728386Y626150D03*
X723386D03*
X718386D03*
Y661386D03*
X723386D03*
X728386D03*
G54D38*
X69339Y515836D03*
Y513867D03*
Y511899D03*
Y509930D03*
X57135D03*
Y511899D03*
Y513867D03*
Y515836D03*
X119039Y402421D03*
X131245D03*
X119039Y404389D03*
Y406358D03*
X131245D03*
Y404389D03*
X119039Y410295D03*
X131245D03*
X119039Y408327D03*
X131245D03*
X636349Y300643D03*
Y308517D03*
Y302611D03*
Y304580D03*
Y306549D03*
X648555Y308517D03*
Y300643D03*
Y306549D03*
Y304580D03*
Y302611D03*
G54D65*
X164375Y262559D03*
Y280287D03*
Y274623D03*
Y268223D03*
Y285951D03*
Y292351D03*
Y310079D03*
Y298015D03*
Y303679D03*
Y327807D03*
Y321407D03*
Y315743D03*
Y333471D03*
X292323Y263375D03*
Y269039D03*
Y281103D03*
Y275439D03*
Y286767D03*
Y293167D03*
Y304495D03*
Y310895D03*
Y298831D03*
Y328623D03*
Y322223D03*
Y316559D03*
Y334287D03*
G54D158*
X652139Y382018D03*
X650564D03*
X648989D03*
X647414D03*
Y412752D03*
X648989D03*
X650564D03*
X652139D03*
X667887Y382018D03*
X666312D03*
X664737D03*
X663162D03*
X661588D03*
X660013D03*
X658438D03*
X656863D03*
X655288D03*
X653714D03*
Y412752D03*
X655288D03*
X656863D03*
X658438D03*
X660013D03*
X661588D03*
X663162D03*
X664737D03*
X666312D03*
X667887D03*
X669462Y382018D03*
Y412752D03*
G54D56*
X136097Y449421D03*
G54D48*
X74621Y493618D03*
G54D57*
X120072Y477093D03*
Y484573D03*
X132152Y497692D03*
Y505172D03*
X223314Y62441D03*
Y54961D03*
X231314Y62441D03*
Y54961D03*
X239314Y62441D03*
Y54961D03*
X247314Y62441D03*
Y54961D03*
X252243Y640444D03*
Y632964D03*
X374786Y508277D03*
Y515757D03*
X387362Y548675D03*
Y541195D03*
X424904Y598298D03*
Y590818D03*
X443704Y110425D03*
X435937Y110553D03*
X443704Y117905D03*
X435937Y118033D03*
X459174Y110350D03*
X451401Y110425D03*
X459174Y117830D03*
X451401Y117905D03*
X554740Y473916D03*
Y481396D03*
X571175Y199691D03*
Y207171D03*
X579175Y199691D03*
Y207171D03*
G54D39*
X66190Y506781D03*
X64221D03*
X62253D03*
X60284D03*
Y518985D03*
X62253D03*
X64221D03*
X66190D03*
X116698Y493127D03*
Y505333D03*
X124572Y493127D03*
X122604D03*
X120635D03*
X118666D03*
X124572Y505333D03*
X118666D03*
X120635D03*
X122604D03*
X334362Y550203D03*
X326488D03*
X332394D03*
X330425D03*
X328456D03*
X326488Y562409D03*
X334362D03*
X328456D03*
X330425D03*
X332394D03*
X379286Y524166D03*
X371412D03*
X377318D03*
X375349D03*
X373380D03*
X371412Y536372D03*
X379286D03*
X373380D03*
X375349D03*
X377318D03*
X458200Y81713D03*
X450326D03*
Y93919D03*
X458200D03*
X456232Y81713D03*
X454263D03*
X452294D03*
Y93919D03*
X454263D03*
X456232D03*
G54D168*
X697200Y140140D03*
X693854D03*
X695084Y212132D03*
X698430D03*
G54D84*
X186664Y43163D03*
X209694D03*
X199822Y427779D03*
X222852D03*
X268071Y614545D03*
X291101D03*
X294948Y20101D03*
X317978D03*
X361142Y611345D03*
X384172D03*
G54D66*
X163910Y507731D03*
X160760D03*
X157611D03*
X163910Y510881D03*
X160760D03*
X157611D03*
X163910Y514030D03*
X160760D03*
X157611D03*
X163910Y517180D03*
X160760D03*
X157611D03*
X163910Y520329D03*
X160760D03*
X157611D03*
X163910Y523479D03*
X160760D03*
X157611D03*
X163910Y526629D03*
X160760D03*
X157611D03*
X163910Y529778D03*
X160760D03*
X157611D03*
X163910Y532928D03*
X160760D03*
X157611D03*
X163910Y536077D03*
X160760D03*
X157611D03*
X163910Y539227D03*
X160760D03*
X157611D03*
X163910Y542377D03*
X160760D03*
X157611D03*
X163910Y545526D03*
X160760D03*
X157611D03*
X163910Y548676D03*
X160760D03*
X157611D03*
X163910Y551825D03*
X160760D03*
X157611D03*
X163910Y554975D03*
X160760D03*
X157611D03*
X179658Y507731D03*
X176508D03*
X179658Y510881D03*
X176508D03*
X179658Y514030D03*
X176508D03*
X179658Y517180D03*
X176508D03*
X179658Y520329D03*
X176508D03*
X179658Y523479D03*
X176508D03*
X179658Y526629D03*
X176508D03*
X179658Y529778D03*
X176508D03*
X179658Y532928D03*
X176508D03*
X179658Y536077D03*
X176508D03*
X179658Y539227D03*
X176508D03*
X179658Y542377D03*
X176508D03*
X179658Y545526D03*
X176508D03*
X179658Y548676D03*
X176508D03*
X179658Y551825D03*
X176508D03*
X179658Y554975D03*
X176508D03*
X182807Y507731D03*
Y510881D03*
Y514030D03*
Y517180D03*
Y520329D03*
Y523479D03*
Y526629D03*
Y529778D03*
Y532928D03*
Y536077D03*
Y539227D03*
Y542377D03*
Y545526D03*
Y548676D03*
Y551825D03*
Y554975D03*
X225755Y497872D03*
Y501022D03*
Y504171D03*
Y507321D03*
Y510471D03*
Y513620D03*
Y516770D03*
Y519919D03*
Y523069D03*
Y526219D03*
Y529368D03*
Y532518D03*
Y535667D03*
Y538817D03*
Y541967D03*
Y545116D03*
Y548266D03*
Y551415D03*
Y554565D03*
Y557715D03*
Y560864D03*
Y564014D03*
X228905Y497872D03*
Y501022D03*
X232054Y497872D03*
Y501022D03*
X235204Y497872D03*
Y501022D03*
X238354Y497872D03*
Y501022D03*
X241503Y497872D03*
Y501022D03*
X228905Y504171D03*
Y507321D03*
Y510471D03*
Y513620D03*
Y516770D03*
X232054Y504171D03*
Y507321D03*
Y510471D03*
Y513620D03*
Y516770D03*
X235204Y504171D03*
Y507321D03*
Y510471D03*
Y513620D03*
Y516770D03*
X238354Y504171D03*
Y507321D03*
Y510471D03*
Y513620D03*
Y516770D03*
X241503Y504171D03*
Y507321D03*
Y510471D03*
X228905Y519919D03*
Y523069D03*
Y526219D03*
Y529368D03*
Y532518D03*
X232054Y519919D03*
Y523069D03*
Y526219D03*
Y529368D03*
Y532518D03*
X235204Y519919D03*
Y523069D03*
Y526219D03*
Y529368D03*
Y532518D03*
X238354Y519919D03*
Y523069D03*
Y526219D03*
Y529368D03*
Y532518D03*
X241503Y519919D03*
Y523069D03*
Y526219D03*
Y529368D03*
Y532518D03*
X228905Y535667D03*
Y538817D03*
Y541967D03*
Y545116D03*
Y548266D03*
X232054Y535667D03*
Y538817D03*
Y541967D03*
Y545116D03*
Y548266D03*
X235204Y535667D03*
Y538817D03*
Y541967D03*
Y545116D03*
Y548266D03*
X238354Y535667D03*
Y538817D03*
Y541967D03*
Y545116D03*
Y548266D03*
X241503Y535667D03*
Y538817D03*
Y541967D03*
X228905Y551415D03*
Y554565D03*
Y557715D03*
Y560864D03*
Y564014D03*
X232054Y551415D03*
Y554565D03*
Y557715D03*
Y560864D03*
Y564014D03*
X235204Y551415D03*
Y554565D03*
Y557715D03*
Y560864D03*
Y564014D03*
X238354Y551415D03*
Y554565D03*
Y557715D03*
Y560864D03*
Y564014D03*
X241503Y551415D03*
Y554565D03*
Y557715D03*
Y560864D03*
Y564014D03*
X244653Y497872D03*
Y501022D03*
X247802Y497872D03*
Y501022D03*
X250952Y497872D03*
Y501022D03*
X254102Y497872D03*
Y501022D03*
X257251Y497872D03*
Y501022D03*
X244653Y504171D03*
Y507321D03*
Y510471D03*
X247802Y504171D03*
Y507321D03*
Y510471D03*
Y513620D03*
X250952Y504171D03*
Y507321D03*
Y510471D03*
Y513620D03*
X254102Y504171D03*
Y507321D03*
Y510471D03*
Y513620D03*
X257251Y504171D03*
Y507321D03*
Y510471D03*
Y513620D03*
X250952Y523069D03*
Y526219D03*
Y529368D03*
Y532518D03*
X254102Y523069D03*
Y526219D03*
Y529368D03*
Y532518D03*
X257251Y523069D03*
Y526219D03*
Y529368D03*
Y532518D03*
X247802Y548266D03*
X250952Y535667D03*
Y538817D03*
Y548266D03*
X254102Y535667D03*
Y538817D03*
Y548266D03*
X257251Y535667D03*
Y538817D03*
Y548266D03*
X244653Y551415D03*
Y554565D03*
Y557715D03*
Y560864D03*
Y564014D03*
X247802Y551415D03*
Y554565D03*
Y557715D03*
Y560864D03*
Y564014D03*
X250952Y551415D03*
Y554565D03*
Y557715D03*
Y560864D03*
Y564014D03*
X254102Y551415D03*
Y554565D03*
Y557715D03*
Y560864D03*
Y564014D03*
X257251Y551415D03*
Y554565D03*
Y557715D03*
Y560864D03*
Y564014D03*
X260401Y497872D03*
Y501022D03*
X263550Y497872D03*
Y501022D03*
X266700Y497872D03*
Y501022D03*
X269850Y497872D03*
Y501022D03*
X272999Y497872D03*
Y501022D03*
X260401Y504171D03*
Y507321D03*
Y510471D03*
Y513620D03*
X263550Y504171D03*
Y507321D03*
Y510471D03*
Y513620D03*
X266700Y504171D03*
Y507321D03*
Y510471D03*
Y513620D03*
X269850Y504171D03*
Y507321D03*
Y510471D03*
Y513620D03*
X272999Y504171D03*
Y507321D03*
Y510471D03*
X260401Y523069D03*
Y526219D03*
Y529368D03*
Y532518D03*
X263550Y523069D03*
Y526219D03*
Y529368D03*
Y532518D03*
X266700Y523069D03*
Y526219D03*
Y529368D03*
Y532518D03*
X260401Y535667D03*
Y538817D03*
Y548266D03*
X263550Y535667D03*
Y538817D03*
Y548266D03*
X266700Y535667D03*
Y538817D03*
Y548266D03*
X269850D03*
X260401Y551415D03*
Y554565D03*
Y557715D03*
Y560864D03*
Y564014D03*
X263550Y551415D03*
Y554565D03*
Y557715D03*
Y560864D03*
Y564014D03*
X266700Y551415D03*
Y554565D03*
Y557715D03*
Y560864D03*
Y564014D03*
X269850Y551415D03*
Y554565D03*
Y557715D03*
Y560864D03*
Y564014D03*
X272999Y551415D03*
Y554565D03*
Y557715D03*
Y560864D03*
Y564014D03*
X276149Y497872D03*
Y501022D03*
X279298Y497872D03*
Y501022D03*
X282448Y497872D03*
Y501022D03*
X285598Y497872D03*
Y501022D03*
X288747Y497872D03*
Y501022D03*
X276149Y504171D03*
Y507321D03*
Y510471D03*
X279298Y504171D03*
Y507321D03*
Y510471D03*
Y513620D03*
X282448Y504171D03*
Y507321D03*
Y510471D03*
Y513620D03*
X285598Y504171D03*
Y507321D03*
Y510471D03*
Y513620D03*
X288747Y504171D03*
Y507321D03*
Y510471D03*
Y513620D03*
X279298Y516770D03*
X282448D03*
X285598D03*
X288747D03*
X276149Y519919D03*
Y523069D03*
Y526219D03*
Y529368D03*
Y532518D03*
X279298Y519919D03*
Y523069D03*
Y526219D03*
Y529368D03*
Y532518D03*
X282448Y519919D03*
Y523069D03*
Y526219D03*
Y529368D03*
Y532518D03*
X285598Y519919D03*
Y523069D03*
Y526219D03*
Y529368D03*
Y532518D03*
X288747Y519919D03*
Y523069D03*
Y526219D03*
Y529368D03*
Y532518D03*
X276149Y535667D03*
Y538817D03*
Y541967D03*
X279298Y535667D03*
Y538817D03*
Y541967D03*
Y545116D03*
Y548266D03*
X282448Y535667D03*
Y538817D03*
Y541967D03*
Y545116D03*
Y548266D03*
X285598Y535667D03*
Y538817D03*
Y541967D03*
Y545116D03*
Y548266D03*
X288747Y535667D03*
Y538817D03*
Y541967D03*
Y545116D03*
Y548266D03*
X276149Y551415D03*
Y554565D03*
Y557715D03*
Y560864D03*
Y564014D03*
X279298Y551415D03*
Y554565D03*
Y557715D03*
Y560864D03*
Y564014D03*
X282448Y551415D03*
Y554565D03*
Y557715D03*
Y560864D03*
Y564014D03*
X285598Y551415D03*
Y554565D03*
Y557715D03*
Y560864D03*
Y564014D03*
X288747Y551415D03*
Y554565D03*
Y557715D03*
Y560864D03*
Y564014D03*
X291897Y497872D03*
Y501022D03*
Y504171D03*
Y507321D03*
Y510471D03*
Y513620D03*
Y516770D03*
Y519919D03*
Y523069D03*
Y526219D03*
Y529368D03*
Y532518D03*
Y535667D03*
Y538817D03*
Y541967D03*
Y545116D03*
Y548266D03*
Y551415D03*
Y554565D03*
Y557715D03*
Y560864D03*
Y564014D03*
G54D75*
X164920Y246805D03*
Y250005D03*
X168120Y246805D03*
X171320D03*
X168120Y250005D03*
X171320D03*
X174520Y246805D03*
X164920Y256405D03*
Y253205D03*
X171320D03*
X168120D03*
X164920Y340441D03*
Y343641D03*
X171320D03*
X168120D03*
X174520Y350041D03*
X171320D03*
X168120Y346841D03*
X171320D03*
X285378Y246805D03*
Y250005D03*
X282178Y246805D03*
X288578D03*
Y250005D03*
X285378Y253205D03*
X288578D03*
X285378Y343641D03*
X288578D03*
X282178Y350041D03*
X285378Y346841D03*
X288578Y350041D03*
X285378D03*
X288578Y346841D03*
X291778Y246805D03*
Y250005D03*
Y256405D03*
Y253205D03*
Y340441D03*
Y343641D03*
Y350041D03*
Y346841D03*
G54D159*
X645840Y381668D03*
Y413102D03*
X671036Y381668D03*
Y413102D03*
G54D93*
X210709Y541953D03*
G54D49*
X88150Y575352D03*
X97150D03*
X106150D03*
G54D58*
X132438Y699863D03*
X130470D03*
X128501D03*
Y717383D03*
X130470D03*
X132438D03*
X136375Y699863D03*
X134406D03*
Y717383D03*
X136375D03*
G54D67*
X157550Y595169D03*
Y597138D03*
Y599106D03*
Y601075D03*
Y603043D03*
Y605012D03*
Y606980D03*
Y608949D03*
Y610917D03*
Y612886D03*
Y614854D03*
Y616823D03*
Y618791D03*
Y620760D03*
Y622728D03*
Y624697D03*
X193376Y597138D03*
Y595169D03*
Y612886D03*
Y610917D03*
Y608949D03*
Y606980D03*
Y605012D03*
Y603043D03*
Y601075D03*
Y599106D03*
Y624697D03*
Y622728D03*
Y620760D03*
Y618791D03*
Y616823D03*
Y614854D03*
X616024Y587981D03*
Y589950D03*
Y591918D03*
Y593887D03*
Y595855D03*
Y597824D03*
Y599792D03*
Y601761D03*
Y603729D03*
Y605698D03*
Y607666D03*
Y609635D03*
Y611603D03*
Y613572D03*
Y615540D03*
Y617509D03*
X651850Y595855D03*
Y593887D03*
Y591918D03*
Y589950D03*
Y587981D03*
Y611603D03*
Y609635D03*
Y607666D03*
Y605698D03*
Y603729D03*
Y601761D03*
Y599792D03*
Y597824D03*
Y617509D03*
Y615540D03*
Y613572D03*
G54D76*
X177720Y246805D03*
Y350041D03*
X278978Y246805D03*
Y350041D03*
G54D85*
X193300Y246260D03*
X187636D03*
X181236D03*
X180422Y350586D03*
X186822D03*
X192486D03*
X211028Y246260D03*
X205364D03*
X198964D03*
X204550Y350586D03*
X198150D03*
X210214D03*
X216692Y246260D03*
X223092D03*
X222278Y350586D03*
X215878D03*
X234420Y246260D03*
X240820D03*
X228756D03*
X227942Y350586D03*
X240006D03*
X233606D03*
X252148Y246260D03*
X246484D03*
X258548D03*
X245670Y350586D03*
X251334D03*
X257734D03*
X269876Y246260D03*
X264212D03*
X263398Y350586D03*
X269062D03*
X276276Y246260D03*
X275462Y350586D03*
G54D94*
X208430Y599735D03*
X198210Y601459D03*
X595294Y260495D03*
X605890Y258785D03*
X625835Y400347D03*
X637543Y399147D03*
G54D169*
X685246Y592423D03*
G54D68*
X162668Y592020D03*
X160699D03*
Y627846D03*
X162668D03*
X178416Y592020D03*
X176447D03*
X174479D03*
X172510D03*
X170542D03*
X168573D03*
X166605D03*
X164636D03*
Y627846D03*
X166605D03*
X168573D03*
X170542D03*
X172510D03*
X174479D03*
X176447D03*
X178416D03*
X190227Y592020D03*
X188258D03*
X186290D03*
X184321D03*
X182353D03*
X180384D03*
Y627846D03*
X182353D03*
X184321D03*
X186290D03*
X188258D03*
X190227D03*
X621142Y584832D03*
X619173D03*
Y620658D03*
X621142D03*
X636890Y584832D03*
X634921D03*
X632953D03*
X630984D03*
X629016D03*
X627047D03*
X625079D03*
X623110D03*
Y620658D03*
X625079D03*
X627047D03*
X629016D03*
X630984D03*
X632953D03*
X634921D03*
X636890D03*
X648701Y584832D03*
X646732D03*
X644764D03*
X642795D03*
X640827D03*
X638858D03*
Y620658D03*
X640827D03*
X642795D03*
X644764D03*
X646732D03*
X648701D03*
G54D86*
X197429Y393326D03*
G54D59*
X143779Y37407D03*
Y38982D03*
Y40557D03*
Y42132D03*
Y43707D03*
X156085D03*
Y42132D03*
Y40557D03*
Y38982D03*
Y37407D03*
X413105Y524007D03*
Y538181D03*
X433127Y524007D03*
Y538181D03*
G54D77*
X175572Y249980D03*
X178812Y257697D03*
X169684Y255495D03*
X168121Y257802D03*
X170272Y259883D03*
X172982Y260548D03*
X173177Y257783D03*
X177312Y260229D03*
X175812Y265293D03*
X178812D03*
X171095Y262559D03*
X168095Y262759D03*
X166332Y265399D03*
X170102Y265191D03*
X172982Y264570D03*
X175572Y252980D03*
X177583Y254867D03*
X178248Y252157D03*
X173561Y254867D03*
X177312Y273113D03*
Y275869D03*
X175812Y268049D03*
X178812D03*
X166778Y269599D03*
X169684Y269723D03*
X168338Y267316D03*
X172426Y270085D03*
X172914Y267355D03*
X172426Y272841D03*
X173177Y275511D03*
X169684Y273223D03*
X168321Y275630D03*
X166771Y273247D03*
X172982Y278276D03*
X170272Y277611D03*
X166122Y277297D03*
X168095Y280487D03*
X171095Y280287D03*
X178812Y280933D03*
X175812D03*
X177312Y288753D03*
X172914Y285083D03*
X168338Y285044D03*
X166332Y283127D03*
X178812Y283689D03*
X175812D03*
X172982Y282298D03*
X170102Y282919D03*
X172426Y287813D03*
X169684Y287451D03*
X166778Y287327D03*
X166771Y290975D03*
X172426Y290569D03*
X173177Y293239D03*
X168321Y293358D03*
X169684Y290951D03*
X177312Y291509D03*
X170272Y295339D03*
X166122Y295025D03*
X172982Y296004D03*
X175812Y296573D03*
X178812D03*
X168095Y298215D03*
X171095Y298015D03*
X172982Y300026D03*
X175812Y299329D03*
X178812D03*
X177312Y304393D03*
Y307149D03*
X168338Y302772D03*
X170102Y300647D03*
X166332Y300855D03*
X172914Y302811D03*
X166771Y308703D03*
X172426Y308297D03*
Y305541D03*
X173177Y310967D03*
X168321Y311086D03*
X169684Y308679D03*
Y305179D03*
X166778Y305055D03*
X178812Y312213D03*
X175812D03*
X170272Y313067D03*
X166122Y312753D03*
X178812Y314969D03*
X175812D03*
X172982Y313732D03*
X177312Y320033D03*
Y322789D03*
X175812Y327853D03*
X178812D03*
X172914Y320539D03*
X172982Y317754D03*
X168338Y320500D03*
X170102Y318375D03*
X166332Y318583D03*
X168095Y315943D03*
X171095Y315743D03*
X166771Y326431D03*
X172426Y323269D03*
X169684Y322907D03*
X166778Y322783D03*
X169684Y326407D03*
X168321Y328814D03*
X173177Y328695D03*
X172426Y326025D03*
X175812Y338429D03*
Y330609D03*
X178812D03*
X166122Y330481D03*
X170272Y330795D03*
X172982Y331460D03*
X171095Y333471D03*
X168095Y333671D03*
X170272Y336147D03*
X168121Y338228D03*
X172982Y335482D03*
X172914Y338267D03*
X172426Y340997D03*
X169684Y340535D03*
X179554Y342047D03*
X176768Y341979D03*
X179579Y336149D03*
Y339149D03*
X174757Y343866D03*
X177433Y344689D03*
X179515Y346623D03*
X174757Y346866D03*
X193100Y249980D03*
X180229Y250206D03*
X188543Y250223D03*
X182612Y248656D03*
X186260Y248663D03*
X190460Y248217D03*
X182636Y251569D03*
X186136D03*
X190668Y251987D03*
X180312Y260229D03*
X181812Y265293D03*
X193300Y252980D03*
X195311Y254867D03*
X191289D03*
X183279Y260697D03*
Y257697D03*
X191099Y259197D03*
Y265197D03*
Y262197D03*
X188343Y259197D03*
Y265197D03*
Y262197D03*
X180348Y255062D03*
X183018Y254311D03*
X185774D03*
X188504Y254826D03*
X189312Y273113D03*
Y275869D03*
X186312D03*
X183312D03*
X186312Y273113D03*
X183312D03*
X192312Y275869D03*
Y273113D03*
X187812Y268049D03*
X184812D03*
X180312Y275869D03*
Y273113D03*
X181812Y268049D03*
Y280933D03*
X184812D03*
X187812D03*
X190812D03*
X193812D03*
X191099Y268197D03*
X195312Y291509D03*
Y288753D03*
X180312D03*
Y291509D03*
X183312Y288753D03*
X186312D03*
X183312Y291509D03*
X186312D03*
X189312D03*
Y288753D03*
X192312D03*
Y291509D03*
X181812Y283689D03*
X184812D03*
X187812D03*
X190812D03*
X193812D03*
X181812Y296573D03*
X190812D03*
X187812D03*
X184812D03*
X193812D03*
X181812Y299329D03*
X190812D03*
X187812D03*
X184812D03*
X193812D03*
X195312Y304393D03*
Y307149D03*
X180312D03*
Y304393D03*
X189312D03*
Y307149D03*
X186312D03*
X183312D03*
X186312Y304393D03*
X183312D03*
X192312Y307149D03*
Y304393D03*
X181812Y312213D03*
X184812D03*
X187812D03*
X190812D03*
X193812D03*
X181812Y314969D03*
X184812D03*
X187812D03*
X190812D03*
X193812D03*
X183312Y320033D03*
X186312D03*
X189312D03*
X181812Y327853D03*
X183312Y322789D03*
X186312D03*
X189312D03*
X184812Y327853D03*
X187812D03*
X190812D03*
X192312Y320033D03*
Y322789D03*
X180312Y320033D03*
Y322789D03*
X195219Y321149D03*
Y324149D03*
Y327149D03*
X190475Y341979D03*
X187710Y341784D03*
X187399Y334649D03*
Y331649D03*
X190155Y334649D03*
Y331649D03*
Y337649D03*
X187399D03*
X182335Y333149D03*
Y336149D03*
Y339149D03*
X189810Y344689D03*
X194497Y341979D03*
X192486Y343866D03*
X182284Y342535D03*
X185040D03*
X195219Y330149D03*
Y333149D03*
Y336149D03*
Y339149D03*
X195118Y344859D03*
X189496Y348839D03*
X192686Y346866D03*
X185446Y348190D03*
X181922Y345277D03*
X185422D03*
X187829Y346640D03*
X181798Y348183D03*
X195326Y348629D03*
X210828Y249980D03*
X197957Y250206D03*
X206271Y250223D03*
X196290Y248007D03*
X200340Y248656D03*
X208188Y248217D03*
X203988Y248663D03*
X200364Y251569D03*
X208396Y251987D03*
X203864Y251569D03*
X211028Y252980D03*
X196163Y263697D03*
Y257697D03*
Y260697D03*
X198919Y263697D03*
Y257697D03*
Y260697D03*
X206739Y262197D03*
Y265197D03*
Y259197D03*
X203983Y262197D03*
Y265197D03*
Y259197D03*
X195976Y252157D03*
X200746Y254311D03*
X203502D03*
X198076Y255062D03*
X209017Y254867D03*
X206232Y254826D03*
X196812Y280933D03*
X199812D03*
X205118Y276767D03*
X201574D03*
X207874D03*
X196163Y275697D03*
Y272697D03*
Y269697D03*
X198919Y275697D03*
Y272697D03*
Y269697D03*
X206739Y268197D03*
Y271197D03*
Y274197D03*
X203983Y268197D03*
Y271197D03*
Y274197D03*
X196163Y266697D03*
X198919D03*
X198312Y288753D03*
Y291509D03*
X201068Y288753D03*
Y291509D03*
X201412Y294265D03*
Y285997D03*
X196812Y283689D03*
X199812D03*
X196812Y296573D03*
X199812D03*
X196812Y299329D03*
X199812D03*
X201412Y301637D03*
X201068Y304393D03*
Y307149D03*
X201412Y309905D03*
X198312Y307149D03*
Y304393D03*
X196812Y312213D03*
X199812D03*
X196812Y314969D03*
X199812D03*
X210859Y321149D03*
Y327149D03*
Y324149D03*
X207874Y320079D03*
X204724D03*
X201968D03*
X205795Y322649D03*
X203039D03*
Y325649D03*
X205795D03*
Y328649D03*
X203039D03*
X197975Y321149D03*
Y324149D03*
Y327149D03*
X201868Y317323D03*
X197282Y342047D03*
X205438Y341784D03*
X208203Y341979D03*
X210859Y336149D03*
Y333149D03*
Y330149D03*
Y339149D03*
X203039Y337649D03*
X205795D03*
Y331649D03*
Y334649D03*
X203039Y331649D03*
Y334649D03*
X197975Y330149D03*
Y333149D03*
Y336149D03*
Y339149D03*
X200012Y342535D03*
X207538Y344689D03*
X202768Y342535D03*
X210214Y343866D03*
X203174Y348190D03*
X197243Y346623D03*
X199650Y345277D03*
X199526Y348183D03*
X207224Y348839D03*
X205557Y346640D03*
X203150Y345277D03*
X210414Y346866D03*
X223999Y250223D03*
X215685Y250206D03*
X214018Y248007D03*
X218068Y248656D03*
X221716Y248663D03*
X225916Y248217D03*
X221592Y251569D03*
X218092D03*
X222379Y259197D03*
X219623D03*
Y265197D03*
Y262197D03*
X222379Y265197D03*
Y262197D03*
X214559Y260697D03*
Y257697D03*
Y263697D03*
X211803Y260697D03*
Y257697D03*
Y263697D03*
X213704Y252157D03*
X213039Y254867D03*
X223960Y254826D03*
X215804Y255062D03*
X221230Y254311D03*
X218474D03*
X226124Y251987D03*
X226745Y254867D03*
X220868Y276767D03*
X211803Y275697D03*
X214559D03*
X217324Y276767D03*
X223624D03*
X219623Y274197D03*
X222379D03*
Y271197D03*
X219623D03*
Y268197D03*
X222379D03*
X214559Y269697D03*
Y272697D03*
X211803Y269697D03*
Y272697D03*
X214559Y266697D03*
X211803D03*
X217324Y320079D03*
X223624D03*
X220080D03*
X218679Y328649D03*
X221435D03*
Y325649D03*
X218679D03*
Y322649D03*
X221435D03*
X213615Y321149D03*
Y327149D03*
Y324149D03*
X226499Y321149D03*
Y324149D03*
Y327149D03*
X223166Y341784D03*
X215010Y342047D03*
X212225Y341979D03*
X218679Y334649D03*
Y331649D03*
X221435Y334649D03*
Y331649D03*
Y337649D03*
X218679D03*
X213615Y336149D03*
Y333149D03*
Y330149D03*
Y339149D03*
X212846Y344859D03*
X217740Y342535D03*
X220496D03*
X225931Y341979D03*
X226499Y330149D03*
Y333149D03*
Y336149D03*
Y339149D03*
X225266Y344689D03*
X220902Y348190D03*
X213054Y348629D03*
X217254Y348183D03*
X224952Y348839D03*
X217378Y345277D03*
X220878D03*
X223285Y346640D03*
X214971Y346623D03*
X233413Y250206D03*
X241727Y250223D03*
X228556Y249980D03*
X235796Y248656D03*
X239444Y248663D03*
X231746Y248007D03*
X239320Y251569D03*
X235820D03*
X243083Y260697D03*
Y257697D03*
Y263697D03*
X230199D03*
Y257697D03*
Y260697D03*
X238019Y262197D03*
Y265197D03*
X235263Y262197D03*
Y265197D03*
Y259197D03*
X238019D03*
X231432Y252157D03*
X233532Y255062D03*
X230767Y254867D03*
X238958Y254311D03*
X236202D03*
X241688Y254826D03*
X228756Y252980D03*
X227443Y263697D03*
Y257697D03*
Y260697D03*
X236618Y276767D03*
X230199Y275697D03*
X243083D03*
X233074Y276767D03*
X239374D03*
X243083Y269697D03*
Y272697D03*
X230199D03*
Y269697D03*
X238019Y268197D03*
X235263D03*
Y271197D03*
X238019D03*
Y274197D03*
X235263D03*
X243083Y266697D03*
X230199D03*
X227443Y275697D03*
Y272697D03*
Y269697D03*
Y266697D03*
X242139Y321149D03*
Y327149D03*
Y324149D03*
X233074Y320079D03*
X239374D03*
X235830D03*
X237075Y322649D03*
X234319D03*
Y325649D03*
X237075D03*
Y328649D03*
X234319D03*
X229255Y321149D03*
Y324149D03*
Y327149D03*
X229953Y341979D03*
X232738Y342020D03*
X240894Y341784D03*
X242139Y336149D03*
Y333149D03*
Y330149D03*
Y339149D03*
X234319Y337649D03*
X237075D03*
Y331649D03*
Y334649D03*
X234319Y331649D03*
Y334649D03*
X229255Y330149D03*
Y333149D03*
Y336149D03*
Y339149D03*
X227942Y343866D03*
X242994Y344689D03*
X230574Y344859D03*
X235468Y342535D03*
X238224D03*
X228142Y346866D03*
X238630Y348190D03*
X242680Y348839D03*
X230782Y348629D03*
X234982Y348183D03*
X232699Y346623D03*
X235106Y345277D03*
X238606D03*
X241013Y346640D03*
X251141Y250206D03*
X253524Y248656D03*
X249474Y248007D03*
X246284Y249980D03*
X243644Y248217D03*
X257172Y248663D03*
X253548Y251569D03*
X243852Y251987D03*
X253659Y259197D03*
X250903D03*
Y265197D03*
Y262197D03*
X253659Y265197D03*
Y262197D03*
X249160Y252157D03*
X251260Y255062D03*
X248495Y254867D03*
X253930Y254311D03*
X246484Y252980D03*
X245839Y260697D03*
Y257697D03*
Y263697D03*
X244473Y254867D03*
X257048Y251569D03*
X258723Y263697D03*
Y257697D03*
Y260697D03*
X256686Y254311D03*
X254830Y279523D03*
X254730Y276767D03*
X251974D03*
X248824D03*
X250903Y274197D03*
X253659D03*
Y271197D03*
X250903D03*
Y268197D03*
X253659D03*
X245839Y275697D03*
Y269697D03*
Y272697D03*
Y266697D03*
X256886Y281877D03*
X258723Y275697D03*
Y272697D03*
Y269697D03*
Y266697D03*
X255286Y295209D03*
Y286941D03*
X256886Y284633D03*
Y297517D03*
X258386Y292453D03*
Y289697D03*
X255630Y292453D03*
Y289697D03*
X255286Y302581D03*
Y310849D03*
X256886Y300273D03*
X258386Y305337D03*
Y308093D03*
X255630Y305337D03*
Y308093D03*
X256886Y313157D03*
X248824Y320079D03*
X251580D03*
X249959Y328649D03*
Y325649D03*
Y322649D03*
X252715Y328649D03*
Y325649D03*
Y322649D03*
X244895Y321149D03*
Y327149D03*
Y324149D03*
X256886Y315913D03*
X257779Y321149D03*
Y324149D03*
Y327149D03*
X255124Y320079D03*
X243659Y341979D03*
X247681D03*
X250466Y342047D03*
X249959Y334649D03*
Y331649D03*
Y337649D03*
X252715Y334649D03*
Y331649D03*
Y337649D03*
X244895Y336149D03*
Y333149D03*
Y330149D03*
Y339149D03*
X245670Y343866D03*
X248302Y344859D03*
X253196Y342535D03*
X257779Y330149D03*
Y333149D03*
Y336149D03*
Y339149D03*
X258622Y341784D03*
X255952Y342535D03*
X245870Y346866D03*
X248510Y348629D03*
X252710Y348183D03*
X250427Y346623D03*
X252834Y345277D03*
X256358Y348190D03*
X258741Y346640D03*
X256334Y345277D03*
X268869Y250206D03*
X271252Y248656D03*
X267202Y248007D03*
X259455Y250223D03*
X264012Y249980D03*
X261372Y248217D03*
X271276Y251569D03*
X261580Y251987D03*
X274363Y257697D03*
X266543Y259197D03*
Y265197D03*
Y262197D03*
X269299Y259197D03*
X274363Y260697D03*
Y263697D03*
X269299Y265197D03*
Y262197D03*
X271658Y254311D03*
X266223Y254867D03*
X268988Y255062D03*
X266888Y252157D03*
X274414Y254311D03*
X261479Y257697D03*
Y260697D03*
Y263697D03*
X259416Y254799D03*
X262201Y254867D03*
X264212Y252980D03*
X271886Y268993D03*
X268886D03*
X265886D03*
X264386Y274057D03*
Y276813D03*
X267386Y274057D03*
X270386D03*
X273386D03*
X267386Y276813D03*
X270386D03*
X273386D03*
X262886Y281877D03*
X259886D03*
X265886D03*
X268886D03*
X271886D03*
X261479Y275697D03*
Y269697D03*
Y272697D03*
Y266697D03*
X262886Y284633D03*
X259886D03*
X261386Y289697D03*
Y292453D03*
X262886Y297517D03*
X264386Y292453D03*
Y289697D03*
X259886Y297517D03*
X265886Y284633D03*
X268886D03*
X271886D03*
X268886Y297517D03*
X265886D03*
X270386Y292453D03*
Y289697D03*
X267386D03*
Y292453D03*
X271886Y297517D03*
X273386Y292453D03*
Y289697D03*
X262886Y300273D03*
X259886D03*
X261386Y308093D03*
Y305337D03*
X264386D03*
Y308093D03*
X268886Y300273D03*
X265886D03*
X271886D03*
X267386Y308093D03*
Y305337D03*
X270386D03*
Y308093D03*
X273386Y305337D03*
Y308093D03*
X262886Y313157D03*
X259886D03*
X265886D03*
X268886D03*
X271886D03*
X262886Y315913D03*
X259886D03*
X265886D03*
X268886D03*
X271886D03*
X264386Y320977D03*
Y323733D03*
X270386Y320977D03*
X267386D03*
X273386D03*
X270386Y323733D03*
X273386D03*
X267386D03*
X271886Y328797D03*
X265599Y328649D03*
X268886Y328797D03*
X260535Y321149D03*
Y324149D03*
Y327149D03*
X273419Y339149D03*
Y336149D03*
X265599Y331649D03*
X268355D03*
Y334649D03*
X265599D03*
X268355Y337649D03*
X265599D03*
X260535Y330149D03*
Y333149D03*
Y336149D03*
Y339149D03*
X261387Y341979D03*
X265409D03*
X268194Y342047D03*
X263398Y343866D03*
X260722Y344689D03*
X273680Y342535D03*
X270924D03*
X266030Y344859D03*
X263598Y346866D03*
X260408Y348839D03*
X270438Y348183D03*
X274086Y348190D03*
X274062Y345277D03*
X270562D03*
X268155Y346623D03*
X266238Y348629D03*
X281941Y249980D03*
X277183Y250223D03*
X274900Y248663D03*
X274776Y251569D03*
X280886Y258417D03*
X283784Y258579D03*
X283716Y261364D03*
Y265386D03*
X284272Y255849D03*
X277886Y266237D03*
X280886D03*
X277119Y257697D03*
Y260697D03*
X279930Y254867D03*
X281941Y252980D03*
X279265Y252157D03*
X277144Y254799D03*
X287014Y256311D03*
X288577Y258618D03*
X286426Y260699D03*
X288603Y263175D03*
X285603Y263375D03*
X286426Y266051D03*
X283521Y268151D03*
X284272Y270821D03*
X277886Y268993D03*
X280886D03*
X274886D03*
X279386Y274057D03*
X276386D03*
X279386Y276813D03*
X276386D03*
X283716Y279092D03*
X283784Y276307D03*
X284272Y273577D03*
X274886Y281877D03*
X280886D03*
X277886D03*
X289927Y270415D03*
X288377Y268032D03*
X287014Y270439D03*
X288603Y280903D03*
X290366Y278263D03*
X289920Y274063D03*
X286596Y278471D03*
X288360Y276346D03*
X287014Y273939D03*
X285603Y281103D03*
X283716Y283114D03*
X283521Y285879D03*
X284272Y288549D03*
X280886Y284633D03*
X277886D03*
Y297517D03*
X280886D03*
X279386Y289697D03*
Y292453D03*
X274886Y284633D03*
Y297517D03*
X276386Y292453D03*
Y289697D03*
X283784Y294035D03*
X283716Y296820D03*
X284272Y291305D03*
X286426Y283779D03*
X289927Y288143D03*
X287014Y288167D03*
X288377Y285760D03*
X290366Y295991D03*
X289920Y291791D03*
X286596Y296199D03*
X288360Y294074D03*
X287014Y291667D03*
X277886Y300273D03*
X280886D03*
X279386Y308093D03*
Y305337D03*
X274886Y300273D03*
X276386Y305337D03*
Y308093D03*
X283716Y300842D03*
X283521Y303607D03*
X284272Y306277D03*
X283784Y311763D03*
X284272Y309033D03*
X280886Y313157D03*
X277886D03*
X274886D03*
X286426Y301507D03*
X285603Y298831D03*
X288603Y298631D03*
X289927Y305871D03*
X287014Y305895D03*
X288377Y303488D03*
X289920Y309519D03*
X287014Y309395D03*
X288360Y311802D03*
X280886Y315913D03*
X277886D03*
X274886D03*
X283716Y318570D03*
Y314548D03*
X283521Y321335D03*
X284272Y324005D03*
X279386Y320977D03*
X276386D03*
X279386Y323733D03*
X276386D03*
X284272Y326761D03*
X277886Y328797D03*
X280886D03*
X274886D03*
X286426Y319235D03*
X285603Y316559D03*
X288603Y316359D03*
X290366Y313719D03*
X286596Y313927D03*
X288377Y321216D03*
X289927Y323599D03*
X287014Y323623D03*
Y327123D03*
X289920Y327247D03*
X283784Y329491D03*
X283716Y332276D03*
Y336298D03*
X283521Y339063D03*
X277886Y331553D03*
X280886D03*
X274886D03*
X279386Y336617D03*
X276386D03*
X277886Y339149D03*
X283137Y341979D03*
X279115D03*
X276350Y341784D03*
X281126Y343866D03*
X278450Y344689D03*
X288360Y329530D03*
X286596Y331655D03*
X290366Y331447D03*
X288603Y334087D03*
X285603Y334287D03*
X288577Y339044D03*
X286426Y336963D03*
X287014Y341351D03*
X281126Y346866D03*
X276469Y346640D03*
X290576Y266365D03*
Y284093D03*
Y301821D03*
Y319549D03*
G54D95*
X226331Y13885D03*
Y39081D03*
X245147Y13885D03*
Y39081D03*
G54D87*
X196149Y386396D03*
X193590D03*
Y400255D03*
X196149D03*
X201267Y386396D03*
X198708D03*
Y400255D03*
X201267D03*
G54D78*
X164920Y259605D03*
Y337241D03*
X291778Y259605D03*
Y337241D03*
G54D96*
X254383Y392464D03*
X251824D03*
X249265D03*
X246706D03*
X268052Y440162D03*
X270611D03*
X273170D03*
X275729D03*
X321404Y386129D03*
X318845D03*
X326522D03*
X323963D03*
G54D69*
X163195Y653433D03*
X179731D03*
X629669Y559245D03*
X646205D03*
G54D88*
X190500Y389487D03*
Y392046D03*
Y394605D03*
Y397164D03*
X204358Y392046D03*
Y389487D03*
Y397164D03*
Y394605D03*
G54D97*
X250545Y399984D03*
X322684Y393649D03*
G54D79*
X180546Y432984D03*
X275974Y25379D03*
G54D98*
X260887Y399450D03*
X268761Y403190D03*
Y395710D03*
X634852Y474939D03*
X634787Y501470D03*
X634887Y488270D03*
X642726Y471199D03*
X642761Y484530D03*
X642726Y478679D03*
X642661Y497730D03*
X642761Y492010D03*
X642661Y505210D03*
X680949Y524536D03*
Y532016D03*
X688823Y528276D03*
G54D89*
X196909Y515342D03*
X208209Y504075D03*
X199565Y506454D03*
X205294Y514368D03*
X205247Y508713D03*
X205195Y522335D03*
X221770Y373780D03*
X217818Y368665D03*
X241215Y374601D03*
X237076Y364113D03*
X239309Y482753D03*
X253960Y135933D03*
X247183Y163107D03*
X253083Y182257D03*
X255643Y192767D03*
X256248Y364633D03*
X257226Y374363D03*
X251856Y373544D03*
X249722Y483208D03*
X244390Y483760D03*
X255055Y483635D03*
X267073Y145007D03*
X263575Y364050D03*
X272031Y374583D03*
X263324Y483388D03*
X283593Y144477D03*
X287993Y364451D03*
X295383Y140527D03*
X293053Y154997D03*
X306782Y292461D03*
X293606Y364305D03*
X314893Y140897D03*
X307574Y149601D03*
X315600Y189807D03*
X307420Y354376D03*
X324393Y146984D03*
X328973Y142937D03*
X335295Y717169D03*
X356515Y683743D03*
X378092Y683915D03*
X399606Y377165D03*
X413386Y363385D03*
X403543Y367322D03*
Y387008D03*
X413386Y390945D03*
X427166Y377165D03*
X423229Y367322D03*
Y387008D03*
X447440Y696900D03*
X461244Y696882D03*
X453940Y697445D03*
X477209Y696918D03*
X466683Y697054D03*
X471768Y696891D03*
X643610Y724087D03*
X643000Y734200D03*
X658050Y672117D03*
X658369Y677774D03*
X659029Y710048D03*
X746000Y475000D03*
G54D99*
X271890Y432642D03*
M02*
